FILE_TYPE = MACRO_DRAWING;
SET COLOR_WIRE YELLOW;
SET COLOR_PROP MONO;
SET COLOR_DOT WHITE;
SET COLOR_ARC YELLOW;
SET COLOR_BODY GREEN;
SET COLOR_NOTE MONO;
SET PROP_DISPLAY VALUE;
SET PAGE_NUMBER P88;
FORCEADD OFFPAGE..3
(1600 5200);
FORCEPROP 2 LAST $XR1 87 
J 0
(1904 5200);
DISPLAY 0.638298 (1904 5200);
PAINT MONO (1904 5200);
FORCEPROP 2 LAST $XR0 62 
J 0
(1814 5200);
DISPLAY 0.638298 (1814 5200);
PAINT MONO (1814 5200);
FORCEPROP 2 LAST CDS_LIB mstr_standard
J 0
(1600 5200);
DISPLAY 0.787234 (1600 5200);
PAINT MONO (1600 5200);
DISPLAY INVISIBLE (1600 5200);
FORCEPROP 1 LAST OFFPAGE TRUE
J 0
(1925 5075);
DISPLAY 0.936170 (1925 5075);
PAINT GREEN (1925 5075);
DISPLAY INVISIBLE (1925 5075);
FORCEPROP 1 LAST COMMENT_BODY TRUE
J 0
(1550 5100);
DISPLAY 0.936170 (1550 5100);
PAINT GREEN (1550 5100);
DISPLAY INVISIBLE (1550 5100);
FORCEPROP 2 LAST PATH I1
J 0
(1800 5275);
DISPLAY 0.787234 (1800 5275);
PAINT MONO (1800 5275);
DISPLAY INVISIBLE (1800 5275);
FORCEADD TAP..6
R 2
(-1700 2050);
FORCEPROP 3 LASTPIN (-1750 2050) SIG_NAME M_M_DQ<9>
J 0
(-1740 2060);
DISPLAY 0.659574 (-1740 2060);
PAINT MONO (-1740 2060);
DISPLAY INVISIBLE (-1740 2060);
FORCEPROP 1 LASTPIN (-1750 2050) BN 9
J 2
(-1700 2060);
DISPLAY 0.617021 (-1700 2060);
PAINT PINK (-1700 2060);
FORCEPROP 2 LAST CDS_LIB mstr_standard
J 2
(-1700 2050);
DISPLAY 0.787234 (-1700 2050);
PAINT MONO (-1700 2050);
DISPLAY INVISIBLE (-1700 2050);
FORCEPROP 1 LAST BODY_TYPE PLUMBING
J 2
(-1700 2000);
DISPLAY 1.234043 (-1700 2000);
PAINT GREEN (-1700 2000);
DISPLAY INVISIBLE (-1700 2000);
FORCEPROP 1 LAST HDL_TAP TRUE
J 2
(-2025 1925);
DISPLAY 1.234043 (-2025 1925);
PAINT GREEN (-2025 1925);
DISPLAY INVISIBLE (-2025 1925);
FORCEPROP 1 LAST PATH I100
J 2
(-1700 2050);
DISPLAY 0.936170 (-1700 2050);
PAINT GREEN (-1700 2050);
DISPLAY INVISIBLE (-1700 2050);
FORCEADD TAP..6
R 2
(-1700 2150);
FORCEPROP 3 LASTPIN (-1750 2150) SIG_NAME M_M_DQ<11>
J 0
(-1740 2160);
DISPLAY 0.659574 (-1740 2160);
PAINT MONO (-1740 2160);
DISPLAY INVISIBLE (-1740 2160);
FORCEPROP 1 LASTPIN (-1750 2150) BN 11
J 2
(-1700 2160);
DISPLAY 0.617021 (-1700 2160);
PAINT PINK (-1700 2160);
FORCEPROP 2 LAST CDS_LIB mstr_standard
J 2
(-1700 2150);
DISPLAY 0.787234 (-1700 2150);
PAINT MONO (-1700 2150);
DISPLAY INVISIBLE (-1700 2150);
FORCEPROP 1 LAST BODY_TYPE PLUMBING
J 2
(-1700 2100);
DISPLAY 1.234043 (-1700 2100);
PAINT GREEN (-1700 2100);
DISPLAY INVISIBLE (-1700 2100);
FORCEPROP 1 LAST HDL_TAP TRUE
J 2
(-2025 2025);
DISPLAY 1.234043 (-2025 2025);
PAINT GREEN (-2025 2025);
DISPLAY INVISIBLE (-2025 2025);
FORCEPROP 1 LAST PATH I101
J 2
(-1700 2150);
DISPLAY 0.936170 (-1700 2150);
PAINT GREEN (-1700 2150);
DISPLAY INVISIBLE (-1700 2150);
FORCEADD TAP..6
R 2
(-1700 2200);
FORCEPROP 3 LASTPIN (-1750 2200) SIG_NAME M_M_DQ<12>
J 0
(-1740 2210);
DISPLAY 0.659574 (-1740 2210);
PAINT MONO (-1740 2210);
DISPLAY INVISIBLE (-1740 2210);
FORCEPROP 1 LASTPIN (-1750 2200) BN 12
J 2
(-1700 2210);
DISPLAY 0.617021 (-1700 2210);
PAINT PINK (-1700 2210);
FORCEPROP 2 LAST CDS_LIB mstr_standard
J 2
(-1700 2200);
DISPLAY 0.787234 (-1700 2200);
PAINT MONO (-1700 2200);
DISPLAY INVISIBLE (-1700 2200);
FORCEPROP 1 LAST BODY_TYPE PLUMBING
J 2
(-1700 2150);
DISPLAY 1.234043 (-1700 2150);
PAINT GREEN (-1700 2150);
DISPLAY INVISIBLE (-1700 2150);
FORCEPROP 1 LAST HDL_TAP TRUE
J 2
(-2025 2075);
DISPLAY 1.234043 (-2025 2075);
PAINT GREEN (-2025 2075);
DISPLAY INVISIBLE (-2025 2075);
FORCEPROP 1 LAST PATH I102
J 2
(-1700 2200);
DISPLAY 0.936170 (-1700 2200);
PAINT GREEN (-1700 2200);
DISPLAY INVISIBLE (-1700 2200);
FORCEADD TAP..6
R 2
(-1700 1950);
FORCEPROP 3 LASTPIN (-1750 1950) SIG_NAME M_M_DQ<7>
J 0
(-1740 1960);
DISPLAY 0.659574 (-1740 1960);
PAINT MONO (-1740 1960);
DISPLAY INVISIBLE (-1740 1960);
FORCEPROP 1 LASTPIN (-1750 1950) BN 7
J 2
(-1700 1960);
DISPLAY 0.617021 (-1700 1960);
PAINT PINK (-1700 1960);
FORCEPROP 2 LAST CDS_LIB mstr_standard
J 2
(-1700 1950);
DISPLAY 0.787234 (-1700 1950);
PAINT MONO (-1700 1950);
DISPLAY INVISIBLE (-1700 1950);
FORCEPROP 1 LAST BODY_TYPE PLUMBING
J 2
(-1700 1900);
DISPLAY 1.234043 (-1700 1900);
PAINT GREEN (-1700 1900);
DISPLAY INVISIBLE (-1700 1900);
FORCEPROP 1 LAST HDL_TAP TRUE
J 2
(-2025 1825);
DISPLAY 1.234043 (-2025 1825);
PAINT GREEN (-2025 1825);
DISPLAY INVISIBLE (-2025 1825);
FORCEPROP 1 LAST PATH I103
J 2
(-1700 1950);
DISPLAY 0.936170 (-1700 1950);
PAINT GREEN (-1700 1950);
DISPLAY INVISIBLE (-1700 1950);
FORCEADD TAP..6
R 2
(-1700 1900);
FORCEPROP 3 LASTPIN (-1750 1900) SIG_NAME M_M_DQ<6>
J 0
(-1740 1910);
DISPLAY 0.659574 (-1740 1910);
PAINT MONO (-1740 1910);
DISPLAY INVISIBLE (-1740 1910);
FORCEPROP 1 LASTPIN (-1750 1900) BN 6
J 2
(-1700 1910);
DISPLAY 0.617021 (-1700 1910);
PAINT PINK (-1700 1910);
FORCEPROP 2 LAST CDS_LIB mstr_standard
J 2
(-1700 1900);
DISPLAY 0.787234 (-1700 1900);
PAINT MONO (-1700 1900);
DISPLAY INVISIBLE (-1700 1900);
FORCEPROP 1 LAST BODY_TYPE PLUMBING
J 2
(-1700 1850);
DISPLAY 1.234043 (-1700 1850);
PAINT GREEN (-1700 1850);
DISPLAY INVISIBLE (-1700 1850);
FORCEPROP 1 LAST HDL_TAP TRUE
J 2
(-2025 1775);
DISPLAY 1.234043 (-2025 1775);
PAINT GREEN (-2025 1775);
DISPLAY INVISIBLE (-2025 1775);
FORCEPROP 1 LAST PATH I104
J 2
(-1700 1900);
DISPLAY 0.936170 (-1700 1900);
PAINT GREEN (-1700 1900);
DISPLAY INVISIBLE (-1700 1900);
FORCEADD TAP..6
R 2
(-1700 1850);
FORCEPROP 3 LASTPIN (-1750 1850) SIG_NAME M_M_DQ<5>
J 0
(-1740 1860);
DISPLAY 0.659574 (-1740 1860);
PAINT MONO (-1740 1860);
DISPLAY INVISIBLE (-1740 1860);
FORCEPROP 1 LASTPIN (-1750 1850) BN 5
J 2
(-1700 1860);
DISPLAY 0.617021 (-1700 1860);
PAINT PINK (-1700 1860);
FORCEPROP 2 LAST CDS_LIB mstr_standard
J 2
(-1700 1850);
DISPLAY 0.787234 (-1700 1850);
PAINT MONO (-1700 1850);
DISPLAY INVISIBLE (-1700 1850);
FORCEPROP 1 LAST BODY_TYPE PLUMBING
J 2
(-1700 1800);
DISPLAY 1.234043 (-1700 1800);
PAINT GREEN (-1700 1800);
DISPLAY INVISIBLE (-1700 1800);
FORCEPROP 1 LAST HDL_TAP TRUE
J 2
(-2025 1725);
DISPLAY 1.234043 (-2025 1725);
PAINT GREEN (-2025 1725);
DISPLAY INVISIBLE (-2025 1725);
FORCEPROP 1 LAST PATH I105
J 2
(-1700 1850);
DISPLAY 0.936170 (-1700 1850);
PAINT GREEN (-1700 1850);
DISPLAY INVISIBLE (-1700 1850);
FORCEADD TAP..6
R 2
(-1700 1800);
FORCEPROP 3 LASTPIN (-1750 1800) SIG_NAME M_M_DQ<4>
J 0
(-1740 1810);
DISPLAY 0.659574 (-1740 1810);
PAINT MONO (-1740 1810);
DISPLAY INVISIBLE (-1740 1810);
FORCEPROP 1 LASTPIN (-1750 1800) BN 4
J 2
(-1700 1810);
DISPLAY 0.617021 (-1700 1810);
PAINT PINK (-1700 1810);
FORCEPROP 2 LAST CDS_LIB mstr_standard
J 2
(-1700 1800);
DISPLAY 0.787234 (-1700 1800);
PAINT MONO (-1700 1800);
DISPLAY INVISIBLE (-1700 1800);
FORCEPROP 1 LAST BODY_TYPE PLUMBING
J 2
(-1700 1750);
DISPLAY 1.234043 (-1700 1750);
PAINT GREEN (-1700 1750);
DISPLAY INVISIBLE (-1700 1750);
FORCEPROP 1 LAST HDL_TAP TRUE
J 2
(-2025 1675);
DISPLAY 1.234043 (-2025 1675);
PAINT GREEN (-2025 1675);
DISPLAY INVISIBLE (-2025 1675);
FORCEPROP 1 LAST PATH I106
J 2
(-1700 1800);
DISPLAY 0.936170 (-1700 1800);
PAINT GREEN (-1700 1800);
DISPLAY INVISIBLE (-1700 1800);
FORCEADD TAP..6
R 2
(-1700 1750);
FORCEPROP 3 LASTPIN (-1750 1750) SIG_NAME M_M_DQ<3>
J 0
(-1740 1760);
DISPLAY 0.659574 (-1740 1760);
PAINT MONO (-1740 1760);
DISPLAY INVISIBLE (-1740 1760);
FORCEPROP 1 LASTPIN (-1750 1750) BN 3
J 2
(-1700 1760);
DISPLAY 0.617021 (-1700 1760);
PAINT PINK (-1700 1760);
FORCEPROP 2 LAST CDS_LIB mstr_standard
J 2
(-1700 1750);
DISPLAY 0.787234 (-1700 1750);
PAINT MONO (-1700 1750);
DISPLAY INVISIBLE (-1700 1750);
FORCEPROP 1 LAST BODY_TYPE PLUMBING
J 2
(-1700 1700);
DISPLAY 1.234043 (-1700 1700);
PAINT GREEN (-1700 1700);
DISPLAY INVISIBLE (-1700 1700);
FORCEPROP 1 LAST HDL_TAP TRUE
J 2
(-2025 1625);
DISPLAY 1.234043 (-2025 1625);
PAINT GREEN (-2025 1625);
DISPLAY INVISIBLE (-2025 1625);
FORCEPROP 1 LAST PATH I107
J 2
(-1700 1750);
DISPLAY 0.936170 (-1700 1750);
PAINT GREEN (-1700 1750);
DISPLAY INVISIBLE (-1700 1750);
FORCEADD TAP..6
R 2
(-1700 1600);
FORCEPROP 3 LASTPIN (-1750 1600) SIG_NAME M_M_DQ<0>
J 0
(-1740 1610);
DISPLAY 0.659574 (-1740 1610);
PAINT MONO (-1740 1610);
DISPLAY INVISIBLE (-1740 1610);
FORCEPROP 1 LASTPIN (-1750 1600) BN 0
J 2
(-1700 1610);
DISPLAY 0.617021 (-1700 1610);
PAINT PINK (-1700 1610);
FORCEPROP 2 LAST CDS_LIB mstr_standard
J 2
(-1700 1600);
DISPLAY 0.787234 (-1700 1600);
PAINT MONO (-1700 1600);
DISPLAY INVISIBLE (-1700 1600);
FORCEPROP 1 LAST BODY_TYPE PLUMBING
J 2
(-1700 1550);
DISPLAY 1.234043 (-1700 1550);
PAINT GREEN (-1700 1550);
DISPLAY INVISIBLE (-1700 1550);
FORCEPROP 1 LAST HDL_TAP TRUE
J 2
(-2025 1475);
DISPLAY 1.234043 (-2025 1475);
PAINT GREEN (-2025 1475);
DISPLAY INVISIBLE (-2025 1475);
FORCEPROP 1 LAST PATH I108
J 2
(-1700 1600);
DISPLAY 0.936170 (-1700 1600);
PAINT GREEN (-1700 1600);
DISPLAY INVISIBLE (-1700 1600);
FORCEADD TAP..6
R 2
(-1700 1700);
FORCEPROP 3 LASTPIN (-1750 1700) SIG_NAME M_M_DQ<2>
J 0
(-1740 1710);
DISPLAY 0.659574 (-1740 1710);
PAINT MONO (-1740 1710);
DISPLAY INVISIBLE (-1740 1710);
FORCEPROP 1 LASTPIN (-1750 1700) BN 2
J 2
(-1700 1710);
DISPLAY 0.617021 (-1700 1710);
PAINT PINK (-1700 1710);
FORCEPROP 2 LAST CDS_LIB mstr_standard
J 2
(-1700 1700);
DISPLAY 0.787234 (-1700 1700);
PAINT MONO (-1700 1700);
DISPLAY INVISIBLE (-1700 1700);
FORCEPROP 1 LAST BODY_TYPE PLUMBING
J 2
(-1700 1650);
DISPLAY 1.234043 (-1700 1650);
PAINT GREEN (-1700 1650);
DISPLAY INVISIBLE (-1700 1650);
FORCEPROP 1 LAST HDL_TAP TRUE
J 2
(-2025 1575);
DISPLAY 1.234043 (-2025 1575);
PAINT GREEN (-2025 1575);
DISPLAY INVISIBLE (-2025 1575);
FORCEPROP 1 LAST PATH I109
J 2
(-1700 1700);
DISPLAY 0.936170 (-1700 1700);
PAINT GREEN (-1700 1700);
DISPLAY INVISIBLE (-1700 1700);
FORCEADD PVDDQ_KLM..1
(-1350 2550);
FORCEPROP 3 LASTPIN (-1350 2500) SIG_NAME PVDDQ_KLM\g
J 0
(-1340 2510);
DISPLAY 0.659574 (-1340 2510);
PAINT MONO (-1340 2510);
DISPLAY INVISIBLE (-1340 2510);
FORCEPROP 1 LAST VOLTAGE 1.2V
J 0
(-1395 2507);
DISPLAY 0.340426 (-1395 2507);
PAINT SKYBLUE (-1395 2507);
DISPLAY INVISIBLE (-1395 2507);
FORCEPROP 2 LAST BOM_COST PROC
J 0
(-1350 2555);
PAINT ORANGE (-1350 2555);
DISPLAY INVISIBLE (-1350 2555);
FORCEPROP 2 LAST CDS_LIB mstr_symbols
J 0
(-1350 2550);
PAINT ORANGE (-1350 2550);
DISPLAY INVISIBLE (-1350 2550);
FORCEPROP 1 LAST BODY_TYPE PLUMBING
J 0
(-1395 2507);
DISPLAY 0.340426 (-1395 2507);
PAINT GREEN (-1395 2507);
DISPLAY INVISIBLE (-1395 2507);
FORCEPROP 1 LAST PATH I11
J 0
(-1300 2575);
DISPLAY 0.872340 (-1300 2575);
PAINT AQUA (-1300 2575);
DISPLAY INVISIBLE (-1300 2575);
FORCEPROP 2 LAST ROOM PROC
J 0
(-1350 2650);
DISPLAY 0.787234 (-1350 2650);
PAINT ORANGE (-1350 2650);
DISPLAY INVISIBLE (-1350 2650);
FORCEPROP 1 LAST HDL_POWER PVDDQ_KLM
J 1
(-1350 2600);
DISPLAY 0.872340 (-1350 2600);
PAINT GREEN (-1350 2600);
DISPLAY INVISIBLE (-1350 2600);
FORCEADD TAP..6
R 2
(-1700 1650);
FORCEPROP 3 LASTPIN (-1750 1650) SIG_NAME M_M_DQ<1>
J 0
(-1740 1660);
DISPLAY 0.659574 (-1740 1660);
PAINT MONO (-1740 1660);
DISPLAY INVISIBLE (-1740 1660);
FORCEPROP 1 LASTPIN (-1750 1650) BN 1
J 2
(-1700 1660);
DISPLAY 0.617021 (-1700 1660);
PAINT PINK (-1700 1660);
FORCEPROP 2 LAST CDS_LIB mstr_standard
J 2
(-1700 1650);
DISPLAY 0.787234 (-1700 1650);
PAINT MONO (-1700 1650);
DISPLAY INVISIBLE (-1700 1650);
FORCEPROP 1 LAST BODY_TYPE PLUMBING
J 2
(-1700 1600);
DISPLAY 1.234043 (-1700 1600);
PAINT GREEN (-1700 1600);
DISPLAY INVISIBLE (-1700 1600);
FORCEPROP 1 LAST HDL_TAP TRUE
J 2
(-2025 1525);
DISPLAY 1.234043 (-2025 1525);
PAINT GREEN (-2025 1525);
DISPLAY INVISIBLE (-2025 1525);
FORCEPROP 1 LAST PATH I110
J 2
(-1700 1650);
DISPLAY 0.936170 (-1700 1650);
PAINT GREEN (-1700 1650);
DISPLAY INVISIBLE (-1700 1650);
FORCEADD SCONN288_H44441003..1
(-2450 3100);
FORCEPROP 1 LAST LOCATION J9L1
J 0
(-2900 5000);
DISPLAY 0.617021 (-2900 5000);
PAINT AQUA (-2900 5000);
FORCEPROP 1 LAST PART_NUMBER H44441-003
J 0
(-2900 1100);
DISPLAY 0.617021 (-2900 1100);
PAINT BLUE (-2900 1100);
FORCEPROP 1 LAST MATERIAL SCONN
J 0
(-2900 4950);
DISPLAY 0.617021 (-2900 4950);
PAINT SKYBLUE (-2900 4950);
FORCEPROP 2 LASTPIN (-2950 1600) $PN 146
J 2
(-2960 1610);
DISPLAY 0.617021 (-2960 1610);
PAINT ORANGE (-2960 1610);
FORCEPROP 2 LASTPIN (-2950 1950) $PN 284
J 2
(-2960 1960);
DISPLAY 0.617021 (-2960 1960);
PAINT ORANGE (-2960 1960);
FORCEPROP 2 LASTPIN (-2950 1750) $PN 285
J 2
(-2960 1760);
DISPLAY 0.617021 (-2960 1760);
PAINT ORANGE (-2960 1760);
FORCEPROP 2 LASTPIN (-2950 1700) $PN 141
J 2
(-2960 1710);
DISPLAY 0.617021 (-2960 1710);
PAINT ORANGE (-2960 1710);
FORCEPROP 2 LASTPIN (-2950 1300) $PN 230
J 2
(-2960 1310);
DISPLAY 0.617021 (-2960 1310);
PAINT ORANGE (-2960 1310);
FORCEPROP 2 LASTPIN (-2950 1900) $PN 238
J 2
(-2960 1910);
DISPLAY 0.617021 (-2960 1910);
PAINT ORANGE (-2960 1910);
FORCEPROP 2 LASTPIN (-2950 1850) $PN 140
J 2
(-2960 1860);
DISPLAY 0.617021 (-2960 1860);
PAINT ORANGE (-2960 1860);
FORCEPROP 2 LASTPIN (-2950 1800) $PN 139
J 2
(-2960 1810);
DISPLAY 0.617021 (-2960 1810);
PAINT ORANGE (-2960 1810);
FORCEPROP 2 LASTPIN (-2950 3250) $PN 237
J 2
(-2960 3260);
DISPLAY 0.617021 (-2960 3260);
PAINT ORANGE (-2960 3260);
FORCEPROP 2 LASTPIN (-2950 3200) $PN 93
J 2
(-2960 3210);
DISPLAY 0.617021 (-2960 3210);
PAINT ORANGE (-2960 3210);
FORCEPROP 2 LASTPIN (-2950 3150) $PN 89
J 2
(-2960 3160);
DISPLAY 0.617021 (-2960 3160);
PAINT ORANGE (-2960 3160);
FORCEPROP 2 LASTPIN (-2950 3100) $PN 84
J 2
(-2960 3110);
DISPLAY 0.617021 (-2960 3110);
PAINT ORANGE (-2960 3110);
FORCEPROP 2 LASTPIN (-2950 1500) $PN 144
J 2
(-2960 1510);
DISPLAY 0.617021 (-2960 1510);
PAINT ORANGE (-2960 1510);
FORCEPROP 2 LASTPIN (-2950 1450) $PN 227
J 2
(-2960 1460);
DISPLAY 0.617021 (-2960 1460);
PAINT ORANGE (-2960 1460);
FORCEPROP 2 LASTPIN (-2950 1400) $PN 205
J 2
(-2960 1410);
DISPLAY 0.617021 (-2960 1410);
PAINT ORANGE (-2960 1410);
FORCEPROP 2 LASTPIN (-2950 2200) $PN 58
J 2
(-2960 2210);
DISPLAY 0.617021 (-2960 2210);
PAINT ORANGE (-2960 2210);
FORCEPROP 2 LASTPIN (-2950 2250) $PN 222
J 2
(-2960 2260);
DISPLAY 0.617021 (-2960 2260);
PAINT ORANGE (-2960 2260);
FORCEPROP 2 LASTPIN (-2950 2850) $PN 91
J 2
(-2960 2860);
DISPLAY 0.617021 (-2960 2860);
PAINT ORANGE (-2960 2860);
FORCEPROP 2 LASTPIN (-2950 2800) $PN 87
J 2
(-2960 2810);
DISPLAY 0.617021 (-2960 2810);
PAINT ORANGE (-2960 2810);
FORCEPROP 2 LASTPIN (-2950 2150) $PN 78
J 2
(-2960 2160);
DISPLAY 0.617021 (-2960 2160);
PAINT ORANGE (-2960 2160);
FORCEPROP 2 LASTPIN (-1950 4750) $PN 280
J 0
(-1940 4760);
DISPLAY 0.617021 (-1940 4760);
PAINT ORANGE (-1940 4760);
FORCEPROP 2 LASTPIN (-1950 4700) $PN 135
J 0
(-1940 4710);
DISPLAY 0.617021 (-1940 4710);
PAINT ORANGE (-1940 4710);
FORCEPROP 2 LASTPIN (-1950 4650) $PN 273
J 0
(-1940 4660);
DISPLAY 0.617021 (-1940 4660);
PAINT ORANGE (-1940 4660);
FORCEPROP 2 LASTPIN (-1950 4600) $PN 128
J 0
(-1940 4610);
DISPLAY 0.617021 (-1940 4610);
PAINT ORANGE (-1940 4610);
FORCEPROP 2 LASTPIN (-1950 4550) $PN 282
J 0
(-1940 4560);
DISPLAY 0.617021 (-1940 4560);
PAINT ORANGE (-1940 4560);
FORCEPROP 2 LASTPIN (-1950 4500) $PN 137
J 0
(-1940 4510);
DISPLAY 0.617021 (-1940 4510);
PAINT ORANGE (-1940 4510);
FORCEPROP 2 LASTPIN (-1950 4450) $PN 275
J 0
(-1940 4460);
DISPLAY 0.617021 (-1940 4460);
PAINT ORANGE (-1940 4460);
FORCEPROP 2 LASTPIN (-1950 4400) $PN 130
J 0
(-1940 4410);
DISPLAY 0.617021 (-1940 4410);
PAINT ORANGE (-1940 4410);
FORCEPROP 2 LASTPIN (-1950 4350) $PN 269
J 0
(-1940 4360);
DISPLAY 0.617021 (-1940 4360);
PAINT ORANGE (-1940 4360);
FORCEPROP 2 LASTPIN (-1950 4300) $PN 124
J 0
(-1940 4310);
DISPLAY 0.617021 (-1940 4310);
PAINT ORANGE (-1940 4310);
FORCEPROP 2 LASTPIN (-1950 4250) $PN 262
J 0
(-1940 4260);
DISPLAY 0.617021 (-1940 4260);
PAINT ORANGE (-1940 4260);
FORCEPROP 2 LASTPIN (-1950 4200) $PN 117
J 0
(-1940 4210);
DISPLAY 0.617021 (-1940 4210);
PAINT ORANGE (-1940 4210);
FORCEPROP 2 LASTPIN (-1950 4150) $PN 271
J 0
(-1940 4160);
DISPLAY 0.617021 (-1940 4160);
PAINT ORANGE (-1940 4160);
FORCEPROP 2 LASTPIN (-1950 4100) $PN 126
J 0
(-1940 4110);
DISPLAY 0.617021 (-1940 4110);
PAINT ORANGE (-1940 4110);
FORCEPROP 2 LASTPIN (-1950 4050) $PN 264
J 0
(-1940 4060);
DISPLAY 0.617021 (-1940 4060);
PAINT ORANGE (-1940 4060);
FORCEPROP 2 LASTPIN (-1950 4000) $PN 119
J 0
(-1940 4010);
DISPLAY 0.617021 (-1940 4010);
PAINT ORANGE (-1940 4010);
FORCEPROP 2 LASTPIN (-1950 3950) $PN 258
J 0
(-1940 3960);
DISPLAY 0.617021 (-1940 3960);
PAINT ORANGE (-1940 3960);
FORCEPROP 2 LASTPIN (-1950 3900) $PN 113
J 0
(-1940 3910);
DISPLAY 0.617021 (-1940 3910);
PAINT ORANGE (-1940 3910);
FORCEPROP 2 LASTPIN (-1950 3850) $PN 251
J 0
(-1940 3860);
DISPLAY 0.617021 (-1940 3860);
PAINT ORANGE (-1940 3860);
FORCEPROP 2 LASTPIN (-1950 3800) $PN 106
J 0
(-1940 3810);
DISPLAY 0.617021 (-1940 3810);
PAINT ORANGE (-1940 3810);
FORCEPROP 2 LASTPIN (-1950 3750) $PN 260
J 0
(-1940 3760);
DISPLAY 0.617021 (-1940 3760);
PAINT ORANGE (-1940 3760);
FORCEPROP 2 LASTPIN (-1950 3700) $PN 115
J 0
(-1940 3710);
DISPLAY 0.617021 (-1940 3710);
PAINT ORANGE (-1940 3710);
FORCEPROP 2 LASTPIN (-1950 3650) $PN 253
J 0
(-1940 3660);
DISPLAY 0.617021 (-1940 3660);
PAINT ORANGE (-1940 3660);
FORCEPROP 2 LASTPIN (-1950 3600) $PN 108
J 0
(-1940 3610);
DISPLAY 0.617021 (-1940 3610);
PAINT ORANGE (-1940 3610);
FORCEPROP 2 LASTPIN (-1950 3550) $PN 247
J 0
(-1940 3560);
DISPLAY 0.617021 (-1940 3560);
PAINT ORANGE (-1940 3560);
FORCEPROP 2 LASTPIN (-1950 3500) $PN 102
J 0
(-1940 3510);
DISPLAY 0.617021 (-1940 3510);
PAINT ORANGE (-1940 3510);
FORCEPROP 2 LASTPIN (-1950 3450) $PN 240
J 0
(-1940 3460);
DISPLAY 0.617021 (-1940 3460);
PAINT ORANGE (-1940 3460);
FORCEPROP 2 LASTPIN (-1950 3400) $PN 95
J 0
(-1940 3410);
DISPLAY 0.617021 (-1940 3410);
PAINT ORANGE (-1940 3410);
FORCEPROP 2 LASTPIN (-1950 3350) $PN 249
J 0
(-1940 3360);
DISPLAY 0.617021 (-1940 3360);
PAINT ORANGE (-1940 3360);
FORCEPROP 2 LASTPIN (-1950 3300) $PN 104
J 0
(-1940 3310);
DISPLAY 0.617021 (-1940 3310);
PAINT ORANGE (-1940 3310);
FORCEPROP 2 LASTPIN (-1950 3250) $PN 242
J 0
(-1940 3260);
DISPLAY 0.617021 (-1940 3260);
PAINT ORANGE (-1940 3260);
FORCEPROP 2 LASTPIN (-1950 3200) $PN 97
J 0
(-1940 3210);
DISPLAY 0.617021 (-1940 3210);
PAINT ORANGE (-1940 3210);
FORCEPROP 2 LASTPIN (-1950 3150) $PN 188
J 0
(-1940 3160);
DISPLAY 0.617021 (-1940 3160);
PAINT ORANGE (-1940 3160);
FORCEPROP 2 LASTPIN (-1950 3100) $PN 43
J 0
(-1940 3110);
DISPLAY 0.617021 (-1940 3110);
PAINT ORANGE (-1940 3110);
FORCEPROP 2 LASTPIN (-1950 3050) $PN 181
J 0
(-1940 3060);
DISPLAY 0.617021 (-1940 3060);
PAINT ORANGE (-1940 3060);
FORCEPROP 2 LASTPIN (-1950 3000) $PN 36
J 0
(-1940 3010);
DISPLAY 0.617021 (-1940 3010);
PAINT ORANGE (-1940 3010);
FORCEPROP 2 LASTPIN (-1950 2950) $PN 190
J 0
(-1940 2960);
DISPLAY 0.617021 (-1940 2960);
PAINT ORANGE (-1940 2960);
FORCEPROP 2 LASTPIN (-1950 2900) $PN 45
J 0
(-1940 2910);
DISPLAY 0.617021 (-1940 2910);
PAINT ORANGE (-1940 2910);
FORCEPROP 2 LASTPIN (-1950 2850) $PN 183
J 0
(-1940 2860);
DISPLAY 0.617021 (-1940 2860);
PAINT ORANGE (-1940 2860);
FORCEPROP 2 LASTPIN (-1950 2800) $PN 38
J 0
(-1940 2810);
DISPLAY 0.617021 (-1940 2810);
PAINT ORANGE (-1940 2810);
FORCEPROP 2 LASTPIN (-1950 2750) $PN 177
J 0
(-1940 2760);
DISPLAY 0.617021 (-1940 2760);
PAINT ORANGE (-1940 2760);
FORCEPROP 2 LASTPIN (-1950 2700) $PN 32
J 0
(-1940 2710);
DISPLAY 0.617021 (-1940 2710);
PAINT ORANGE (-1940 2710);
FORCEPROP 2 LASTPIN (-1950 2650) $PN 170
J 0
(-1940 2660);
DISPLAY 0.617021 (-1940 2660);
PAINT ORANGE (-1940 2660);
FORCEPROP 2 LASTPIN (-1950 2600) $PN 25
J 0
(-1940 2610);
DISPLAY 0.617021 (-1940 2610);
PAINT ORANGE (-1940 2610);
FORCEPROP 2 LASTPIN (-1950 2550) $PN 179
J 0
(-1940 2560);
DISPLAY 0.617021 (-1940 2560);
PAINT ORANGE (-1940 2560);
FORCEPROP 2 LASTPIN (-1950 2500) $PN 34
J 0
(-1940 2510);
DISPLAY 0.617021 (-1940 2510);
PAINT ORANGE (-1940 2510);
FORCEPROP 2 LASTPIN (-1950 2400) $PN 27
J 0
(-1940 2410);
DISPLAY 0.617021 (-1940 2410);
PAINT ORANGE (-1940 2410);
FORCEPROP 2 LASTPIN (-1950 2350) $PN 166
J 0
(-1940 2360);
DISPLAY 0.617021 (-1940 2360);
PAINT ORANGE (-1940 2360);
FORCEPROP 2 LASTPIN (-1950 2300) $PN 21
J 0
(-1940 2310);
DISPLAY 0.617021 (-1940 2310);
PAINT ORANGE (-1940 2310);
FORCEPROP 2 LASTPIN (-1950 2250) $PN 159
J 0
(-1940 2260);
DISPLAY 0.617021 (-1940 2260);
PAINT ORANGE (-1940 2260);
FORCEPROP 2 LASTPIN (-1950 2200) $PN 14
J 0
(-1940 2210);
DISPLAY 0.617021 (-1940 2210);
PAINT ORANGE (-1940 2210);
FORCEPROP 2 LASTPIN (-1950 2150) $PN 168
J 0
(-1940 2160);
DISPLAY 0.617021 (-1940 2160);
PAINT ORANGE (-1940 2160);
FORCEPROP 2 LASTPIN (-1950 2100) $PN 23
J 0
(-1940 2110);
DISPLAY 0.617021 (-1940 2110);
PAINT ORANGE (-1940 2110);
FORCEPROP 2 LASTPIN (-1950 2050) $PN 161
J 0
(-1940 2060);
DISPLAY 0.617021 (-1940 2060);
PAINT ORANGE (-1940 2060);
FORCEPROP 2 LASTPIN (-1950 2000) $PN 16
J 0
(-1940 2010);
DISPLAY 0.617021 (-1940 2010);
PAINT ORANGE (-1940 2010);
FORCEPROP 2 LASTPIN (-1950 1950) $PN 155
J 0
(-1940 1960);
DISPLAY 0.617021 (-1940 1960);
PAINT ORANGE (-1940 1960);
FORCEPROP 2 LASTPIN (-1950 1900) $PN 10
J 0
(-1940 1910);
DISPLAY 0.617021 (-1940 1910);
PAINT ORANGE (-1940 1910);
FORCEPROP 2 LASTPIN (-1950 1850) $PN 148
J 0
(-1940 1860);
DISPLAY 0.617021 (-1940 1860);
PAINT ORANGE (-1940 1860);
FORCEPROP 2 LASTPIN (-1950 1800) $PN 3
J 0
(-1940 1810);
DISPLAY 0.617021 (-1940 1810);
PAINT ORANGE (-1940 1810);
FORCEPROP 2 LASTPIN (-1950 1750) $PN 157
J 0
(-1940 1760);
DISPLAY 0.617021 (-1940 1760);
PAINT ORANGE (-1940 1760);
FORCEPROP 2 LASTPIN (-1950 1700) $PN 12
J 0
(-1940 1710);
DISPLAY 0.617021 (-1940 1710);
PAINT ORANGE (-1940 1710);
FORCEPROP 2 LASTPIN (-1950 1650) $PN 150
J 0
(-1940 1660);
DISPLAY 0.617021 (-1940 1660);
PAINT ORANGE (-1940 1660);
FORCEPROP 2 LASTPIN (-1950 1600) $PN 5
J 0
(-1940 1610);
DISPLAY 0.617021 (-1940 1610);
PAINT ORANGE (-1940 1610);
FORCEPROP 2 LASTPIN (-2950 3000) $PN 203
J 2
(-2960 3010);
DISPLAY 0.617021 (-2960 3010);
PAINT ORANGE (-2960 3010);
FORCEPROP 2 LASTPIN (-2950 2950) $PN 60
J 2
(-2960 2960);
DISPLAY 0.617021 (-2960 2960);
PAINT ORANGE (-2960 2960);
FORCEPROP 2 LASTPIN (-2950 3550) $PN 218
J 2
(-2960 3560);
DISPLAY 0.617021 (-2960 3560);
PAINT ORANGE (-2960 3560);
FORCEPROP 2 LASTPIN (-2950 3500) $PN 219
J 2
(-2960 3510);
DISPLAY 0.617021 (-2960 3510);
PAINT ORANGE (-2960 3510);
FORCEPROP 2 LASTPIN (-2950 3450) $PN 74
J 2
(-2960 3460);
DISPLAY 0.617021 (-2960 3460);
PAINT ORANGE (-2960 3460);
FORCEPROP 2 LASTPIN (-2950 3400) $PN 75
J 2
(-2960 3410);
DISPLAY 0.617021 (-2960 3410);
PAINT ORANGE (-2960 3410);
FORCEPROP 2 LASTPIN (-2950 2700) $PN 199
J 2
(-2960 2710);
DISPLAY 0.617021 (-2960 2710);
PAINT ORANGE (-2960 2710);
FORCEPROP 2 LASTPIN (-2950 2650) $PN 54
J 2
(-2960 2660);
DISPLAY 0.617021 (-2960 2660);
PAINT ORANGE (-2960 2660);
FORCEPROP 2 LASTPIN (-2950 2600) $PN 192
J 2
(-2960 2610);
DISPLAY 0.617021 (-2960 2610);
PAINT ORANGE (-2960 2610);
FORCEPROP 2 LASTPIN (-2950 2550) $PN 47
J 2
(-2960 2560);
DISPLAY 0.617021 (-2960 2560);
PAINT ORANGE (-2960 2560);
FORCEPROP 2 LASTPIN (-2950 2500) $PN 201
J 2
(-2960 2510);
DISPLAY 0.617021 (-2960 2510);
PAINT ORANGE (-2960 2510);
FORCEPROP 2 LASTPIN (-2950 2450) $PN 56
J 2
(-2960 2460);
DISPLAY 0.617021 (-2960 2460);
PAINT ORANGE (-2960 2460);
FORCEPROP 2 LASTPIN (-2950 2400) $PN 194
J 2
(-2960 2410);
DISPLAY 0.617021 (-2960 2410);
PAINT ORANGE (-2960 2410);
FORCEPROP 2 LASTPIN (-2950 2350) $PN 49
J 2
(-2960 2360);
DISPLAY 0.617021 (-2960 2360);
PAINT ORANGE (-2960 2360);
FORCEPROP 2 LASTPIN (-2950 3300) $PN 235
J 2
(-2960 3310);
DISPLAY 0.617021 (-2960 3310);
PAINT ORANGE (-2960 3310);
FORCEPROP 2 LASTPIN (-2950 3700) $PN 207
J 2
(-2960 3710);
DISPLAY 0.617021 (-2960 3710);
PAINT ORANGE (-2960 3710);
FORCEPROP 2 LASTPIN (-2950 3650) $PN 63
J 2
(-2960 3660);
DISPLAY 0.617021 (-2960 3660);
PAINT ORANGE (-2960 3660);
FORCEPROP 2 LASTPIN (-2950 3800) $PN 224
J 2
(-2960 3810);
DISPLAY 0.617021 (-2960 3810);
PAINT ORANGE (-2960 3810);
FORCEPROP 2 LASTPIN (-2950 3750) $PN 81
J 2
(-2960 3760);
DISPLAY 0.617021 (-2960 3760);
PAINT ORANGE (-2960 3760);
FORCEPROP 2 LASTPIN (-2950 2100) $PN 208
J 2
(-2960 2110);
DISPLAY 0.617021 (-2960 2110);
PAINT ORANGE (-2960 2110);
FORCEPROP 2 LASTPIN (-2950 2050) $PN 62
J 2
(-2960 2060);
DISPLAY 0.617021 (-2960 2060);
PAINT ORANGE (-2960 2060);
FORCEPROP 2 LASTPIN (-2950 4750) $PN 234
J 2
(-2960 4760);
DISPLAY 0.617021 (-2960 4760);
PAINT ORANGE (-2960 4760);
FORCEPROP 2 LASTPIN (-2950 4700) $PN 82
J 2
(-2960 4710);
DISPLAY 0.617021 (-2960 4710);
PAINT ORANGE (-2960 4710);
FORCEPROP 2 LASTPIN (-2950 4650) $PN 86
J 2
(-2960 4660);
DISPLAY 0.617021 (-2960 4660);
PAINT ORANGE (-2960 4660);
FORCEPROP 2 LASTPIN (-2950 4500) $PN 65
J 2
(-2960 4510);
DISPLAY 0.617021 (-2960 4510);
PAINT ORANGE (-2960 4510);
FORCEPROP 2 LASTPIN (-2950 4450) $PN 210
J 2
(-2960 4460);
DISPLAY 0.617021 (-2960 4460);
PAINT ORANGE (-2960 4460);
FORCEPROP 2 LASTPIN (-2950 4400) $PN 225
J 2
(-2960 4410);
DISPLAY 0.617021 (-2960 4410);
PAINT ORANGE (-2960 4410);
FORCEPROP 2 LASTPIN (-2950 4350) $PN 66
J 2
(-2960 4360);
DISPLAY 0.617021 (-2960 4360);
PAINT ORANGE (-2960 4360);
FORCEPROP 2 LASTPIN (-2950 4300) $PN 68
J 2
(-2960 4310);
DISPLAY 0.617021 (-2960 4310);
PAINT ORANGE (-2960 4310);
FORCEPROP 2 LASTPIN (-2950 4250) $PN 211
J 2
(-2960 4260);
DISPLAY 0.617021 (-2960 4260);
PAINT ORANGE (-2960 4260);
FORCEPROP 2 LASTPIN (-2950 4200) $PN 69
J 2
(-2960 4210);
DISPLAY 0.617021 (-2960 4210);
PAINT ORANGE (-2960 4210);
FORCEPROP 2 LASTPIN (-2950 4150) $PN 213
J 2
(-2960 4160);
DISPLAY 0.617021 (-2960 4160);
PAINT ORANGE (-2960 4160);
FORCEPROP 2 LASTPIN (-2950 4100) $PN 214
J 2
(-2960 4110);
DISPLAY 0.617021 (-2960 4110);
PAINT ORANGE (-2960 4110);
FORCEPROP 2 LASTPIN (-2950 4050) $PN 71
J 2
(-2960 4060);
DISPLAY 0.617021 (-2960 4060);
PAINT ORANGE (-2960 4060);
FORCEPROP 2 LASTPIN (-2950 4000) $PN 216
J 2
(-2960 4010);
DISPLAY 0.617021 (-2960 4010);
PAINT ORANGE (-2960 4010);
FORCEPROP 2 LASTPIN (-2950 3950) $PN 72
J 2
(-2960 3960);
DISPLAY 0.617021 (-2960 3960);
PAINT ORANGE (-2960 3960);
FORCEPROP 2 LASTPIN (-2950 3900) $PN 79
J 2
(-2960 3910);
DISPLAY 0.617021 (-2960 3910);
PAINT ORANGE (-2960 3910);
FORCEPROP 2 LASTPIN (-2950 4600) $PN 228
J 2
(-2960 4610);
DISPLAY 0.617021 (-2960 4610);
PAINT ORANGE (-2960 4610);
FORCEPROP 2 LASTPIN (-2950 4550) $PN 232
J 2
(-2960 4560);
DISPLAY 0.617021 (-2960 4560);
PAINT ORANGE (-2960 4560);
FORCEPROP 2 LASTPIN (-1950 2450) $PN 172
J 0
(-1940 2460);
DISPLAY 0.617021 (-1940 2460);
PAINT ORANGE (-1940 2460);
FORCEPROP 0 LAST BOM_SS NOPOP
J 0
(-2586 5067);
DISPLAY 1.021277 (-2586 5067);
PAINT BROWN (-2586 5067);
DISPLAY BOTH (-2586 5067);
FORCEPROP 1 LAST PACK_TYPE PIP
J 0
(-2900 5050);
PAINT SKYBLUE (-2900 5050);
DISPLAY INVISIBLE (-2900 5050);
FORCEPROP 2 LAST SEC_TYPE PIP
J 0
(-2900 5050);
DISPLAY 1.021277 (-2900 5050);
PAINT ORANGE (-2900 5050);
DISPLAY INVISIBLE (-2900 5050);
FORCEPROP 2 LAST CDS_LIB mstr_sconn
J 0
(-2450 3100);
PAINT ORANGE (-2450 3100);
DISPLAY INVISIBLE (-2450 3100);
FORCEPROP 2 LAST BOM_COST DDR4_CH_M
J 0
(-2450 3100);
PAINT ORANGE (-2450 3100);
DISPLAY INVISIBLE (-2450 3100);
FORCEPROP 2 LAST SEC 1
J 0
(-2900 5050);
DISPLAY 0.680851 (-2900 5050);
PAINT MONO (-2900 5050);
DISPLAY INVISIBLE (-2900 5050);
FORCEPROP 2 LAST CDS_LOCATION J9L1
J 0
(-2900 5000);
DISPLAY 0.617021 (-2900 5000);
PAINT AQUA (-2900 5000);
DISPLAY INVISIBLE (-2900 5000);
FORCEPROP 1 LAST PATH I111
J 0
(-2450 4950);
PAINT GREEN (-2450 4950);
DISPLAY INVISIBLE (-2450 4950);
FORCEPROP 2 LAST ROOM DDR4_CH_M
J 0
(-2450 3100);
PAINT ORANGE (-2450 3100);
DISPLAY INVISIBLE (-2450 3100);
FORCEADD TAP..6
(-3200 4700);
FORCEPROP 3 LASTPIN (-3150 4700) SIG_NAME M_M_MA<16>
J 0
(-3140 4710);
DISPLAY 0.659574 (-3140 4710);
PAINT MONO (-3140 4710);
DISPLAY INVISIBLE (-3140 4710);
FORCEPROP 1 LASTPIN (-3150 4700) BN 16
J 0
(-3200 4710);
DISPLAY 0.617021 (-3200 4710);
PAINT PINK (-3200 4710);
FORCEPROP 2 LAST CDS_LIB mstr_standard
J 2
(-3200 4700);
DISPLAY 0.787234 (-3200 4700);
PAINT MONO (-3200 4700);
DISPLAY INVISIBLE (-3200 4700);
FORCEPROP 1 LAST BODY_TYPE PLUMBING
J 0
(-3200 4650);
DISPLAY 1.234043 (-3200 4650);
PAINT GREEN (-3200 4650);
DISPLAY INVISIBLE (-3200 4650);
FORCEPROP 1 LAST HDL_TAP TRUE
J 0
(-2875 4575);
DISPLAY 1.234043 (-2875 4575);
PAINT GREEN (-2875 4575);
DISPLAY INVISIBLE (-2875 4575);
FORCEPROP 1 LAST PATH I112
J 0
(-3200 4700);
DISPLAY 0.936170 (-3200 4700);
PAINT GREEN (-3200 4700);
DISPLAY INVISIBLE (-3200 4700);
FORCEADD TAP..6
(-3200 4750);
FORCEPROP 3 LASTPIN (-3150 4750) SIG_NAME M_M_MA<17>
J 0
(-3140 4760);
DISPLAY 0.659574 (-3140 4760);
PAINT MONO (-3140 4760);
DISPLAY INVISIBLE (-3140 4760);
FORCEPROP 1 LASTPIN (-3150 4750) BN 17
J 0
(-3200 4760);
DISPLAY 0.617021 (-3200 4760);
PAINT PINK (-3200 4760);
FORCEPROP 2 LAST CDS_LIB mstr_standard
J 0
(-3200 4750);
DISPLAY 0.787234 (-3200 4750);
PAINT MONO (-3200 4750);
DISPLAY INVISIBLE (-3200 4750);
FORCEPROP 1 LAST BODY_TYPE PLUMBING
J 0
(-3200 4700);
DISPLAY 1.234043 (-3200 4700);
PAINT GREEN (-3200 4700);
DISPLAY INVISIBLE (-3200 4700);
FORCEPROP 1 LAST HDL_TAP TRUE
J 0
(-2875 4625);
DISPLAY 1.234043 (-2875 4625);
PAINT GREEN (-2875 4625);
DISPLAY INVISIBLE (-2875 4625);
FORCEPROP 1 LAST PATH I113
J 0
(-3200 4750);
DISPLAY 0.936170 (-3200 4750);
PAINT GREEN (-3200 4750);
DISPLAY INVISIBLE (-3200 4750);
FORCEADD TAP..6
(-3200 4650);
FORCEPROP 3 LASTPIN (-3150 4650) SIG_NAME M_M_MA<15>
J 0
(-3140 4660);
DISPLAY 0.659574 (-3140 4660);
PAINT MONO (-3140 4660);
DISPLAY INVISIBLE (-3140 4660);
FORCEPROP 1 LASTPIN (-3150 4650) BN 15
J 0
(-3200 4660);
DISPLAY 0.617021 (-3200 4660);
PAINT PINK (-3200 4660);
FORCEPROP 2 LAST CDS_LIB mstr_standard
J 2
(-3200 4650);
DISPLAY 0.787234 (-3200 4650);
PAINT MONO (-3200 4650);
DISPLAY INVISIBLE (-3200 4650);
FORCEPROP 1 LAST BODY_TYPE PLUMBING
J 0
(-3200 4600);
DISPLAY 1.234043 (-3200 4600);
PAINT GREEN (-3200 4600);
DISPLAY INVISIBLE (-3200 4600);
FORCEPROP 1 LAST HDL_TAP TRUE
J 0
(-2875 4525);
DISPLAY 1.234043 (-2875 4525);
PAINT GREEN (-2875 4525);
DISPLAY INVISIBLE (-2875 4525);
FORCEPROP 1 LAST PATH I114
J 0
(-3200 4650);
DISPLAY 0.936170 (-3200 4650);
PAINT GREEN (-3200 4650);
DISPLAY INVISIBLE (-3200 4650);
FORCEADD TAP..6
(-3200 4600);
FORCEPROP 3 LASTPIN (-3150 4600) SIG_NAME M_M_MA<14>
J 0
(-3140 4610);
DISPLAY 0.659574 (-3140 4610);
PAINT MONO (-3140 4610);
DISPLAY INVISIBLE (-3140 4610);
FORCEPROP 1 LASTPIN (-3150 4600) BN 14
J 0
(-3200 4610);
DISPLAY 0.617021 (-3200 4610);
PAINT PINK (-3200 4610);
FORCEPROP 2 LAST CDS_LIB mstr_standard
J 2
(-3200 4600);
DISPLAY 0.787234 (-3200 4600);
PAINT MONO (-3200 4600);
DISPLAY INVISIBLE (-3200 4600);
FORCEPROP 1 LAST BODY_TYPE PLUMBING
J 0
(-3200 4550);
DISPLAY 1.234043 (-3200 4550);
PAINT GREEN (-3200 4550);
DISPLAY INVISIBLE (-3200 4550);
FORCEPROP 1 LAST HDL_TAP TRUE
J 0
(-2875 4475);
DISPLAY 1.234043 (-2875 4475);
PAINT GREEN (-2875 4475);
DISPLAY INVISIBLE (-2875 4475);
FORCEPROP 1 LAST PATH I115
J 0
(-3200 4600);
DISPLAY 0.936170 (-3200 4600);
PAINT GREEN (-3200 4600);
DISPLAY INVISIBLE (-3200 4600);
FORCEADD TAP..6
(-3200 4550);
FORCEPROP 3 LASTPIN (-3150 4550) SIG_NAME M_M_MA<13>
J 0
(-3140 4560);
DISPLAY 0.659574 (-3140 4560);
PAINT MONO (-3140 4560);
DISPLAY INVISIBLE (-3140 4560);
FORCEPROP 1 LASTPIN (-3150 4550) BN 13
J 0
(-3200 4560);
DISPLAY 0.617021 (-3200 4560);
PAINT PINK (-3200 4560);
FORCEPROP 2 LAST CDS_LIB mstr_standard
J 2
(-3200 4550);
DISPLAY 0.787234 (-3200 4550);
PAINT MONO (-3200 4550);
DISPLAY INVISIBLE (-3200 4550);
FORCEPROP 1 LAST BODY_TYPE PLUMBING
J 0
(-3200 4500);
DISPLAY 1.234043 (-3200 4500);
PAINT GREEN (-3200 4500);
DISPLAY INVISIBLE (-3200 4500);
FORCEPROP 1 LAST HDL_TAP TRUE
J 0
(-2875 4425);
DISPLAY 1.234043 (-2875 4425);
PAINT GREEN (-2875 4425);
DISPLAY INVISIBLE (-2875 4425);
FORCEPROP 1 LAST PATH I116
J 0
(-3200 4550);
DISPLAY 0.936170 (-3200 4550);
PAINT GREEN (-3200 4550);
DISPLAY INVISIBLE (-3200 4550);
FORCEADD TAP..6
(-3200 4500);
FORCEPROP 3 LASTPIN (-3150 4500) SIG_NAME M_M_MA<12>
J 0
(-3140 4510);
DISPLAY 0.659574 (-3140 4510);
PAINT MONO (-3140 4510);
DISPLAY INVISIBLE (-3140 4510);
FORCEPROP 1 LASTPIN (-3150 4500) BN 12
J 0
(-3200 4510);
DISPLAY 0.617021 (-3200 4510);
PAINT PINK (-3200 4510);
FORCEPROP 2 LAST CDS_LIB mstr_standard
J 2
(-3200 4500);
DISPLAY 0.787234 (-3200 4500);
PAINT MONO (-3200 4500);
DISPLAY INVISIBLE (-3200 4500);
FORCEPROP 1 LAST BODY_TYPE PLUMBING
J 0
(-3200 4450);
DISPLAY 1.234043 (-3200 4450);
PAINT GREEN (-3200 4450);
DISPLAY INVISIBLE (-3200 4450);
FORCEPROP 1 LAST HDL_TAP TRUE
J 0
(-2875 4375);
DISPLAY 1.234043 (-2875 4375);
PAINT GREEN (-2875 4375);
DISPLAY INVISIBLE (-2875 4375);
FORCEPROP 1 LAST PATH I117
J 0
(-3200 4500);
DISPLAY 0.936170 (-3200 4500);
PAINT GREEN (-3200 4500);
DISPLAY INVISIBLE (-3200 4500);
FORCEADD TAP..6
(-3200 4450);
FORCEPROP 3 LASTPIN (-3150 4450) SIG_NAME M_M_MA<11>
J 0
(-3140 4460);
DISPLAY 0.659574 (-3140 4460);
PAINT MONO (-3140 4460);
DISPLAY INVISIBLE (-3140 4460);
FORCEPROP 1 LASTPIN (-3150 4450) BN 11
J 0
(-3200 4460);
DISPLAY 0.617021 (-3200 4460);
PAINT PINK (-3200 4460);
FORCEPROP 2 LAST CDS_LIB mstr_standard
J 2
(-3200 4450);
DISPLAY 0.787234 (-3200 4450);
PAINT MONO (-3200 4450);
DISPLAY INVISIBLE (-3200 4450);
FORCEPROP 1 LAST BODY_TYPE PLUMBING
J 0
(-3200 4400);
DISPLAY 1.234043 (-3200 4400);
PAINT GREEN (-3200 4400);
DISPLAY INVISIBLE (-3200 4400);
FORCEPROP 1 LAST HDL_TAP TRUE
J 0
(-2875 4325);
DISPLAY 1.234043 (-2875 4325);
PAINT GREEN (-2875 4325);
DISPLAY INVISIBLE (-2875 4325);
FORCEPROP 1 LAST PATH I118
J 0
(-3200 4450);
DISPLAY 0.936170 (-3200 4450);
PAINT GREEN (-3200 4450);
DISPLAY INVISIBLE (-3200 4450);
FORCEADD TAP..6
(-3200 4400);
FORCEPROP 3 LASTPIN (-3150 4400) SIG_NAME M_M_MA<10>
J 0
(-3140 4410);
DISPLAY 0.659574 (-3140 4410);
PAINT MONO (-3140 4410);
DISPLAY INVISIBLE (-3140 4410);
FORCEPROP 1 LASTPIN (-3150 4400) BN 10
J 0
(-3200 4410);
DISPLAY 0.617021 (-3200 4410);
PAINT PINK (-3200 4410);
FORCEPROP 2 LAST CDS_LIB mstr_standard
J 2
(-3200 4400);
DISPLAY 0.787234 (-3200 4400);
PAINT MONO (-3200 4400);
DISPLAY INVISIBLE (-3200 4400);
FORCEPROP 1 LAST BODY_TYPE PLUMBING
J 0
(-3200 4350);
DISPLAY 1.234043 (-3200 4350);
PAINT GREEN (-3200 4350);
DISPLAY INVISIBLE (-3200 4350);
FORCEPROP 1 LAST HDL_TAP TRUE
J 0
(-2875 4275);
DISPLAY 1.234043 (-2875 4275);
PAINT GREEN (-2875 4275);
DISPLAY INVISIBLE (-2875 4275);
FORCEPROP 1 LAST PATH I119
J 0
(-3200 4400);
DISPLAY 0.936170 (-3200 4400);
PAINT GREEN (-3200 4400);
DISPLAY INVISIBLE (-3200 4400);
FORCEADD TAP..6
R 2
(900 4500);
FORCEPROP 3 LASTPIN (850 4500) SIG_NAME M_M_DQS_DN<11>
J 0
(860 4510);
DISPLAY 0.659574 (860 4510);
PAINT MONO (860 4510);
DISPLAY INVISIBLE (860 4510);
FORCEPROP 1 LASTPIN (850 4500) BN 11
J 2
(900 4510);
DISPLAY 0.617021 (900 4510);
PAINT PINK (900 4510);
FORCEPROP 2 LAST CDS_LIB mstr_standard
J 0
(900 4500);
DISPLAY 0.787234 (900 4500);
PAINT MONO (900 4500);
DISPLAY INVISIBLE (900 4500);
FORCEPROP 1 LAST BODY_TYPE PLUMBING
J 2
(900 4450);
DISPLAY 1.234043 (900 4450);
PAINT GREEN (900 4450);
DISPLAY INVISIBLE (900 4450);
FORCEPROP 1 LAST HDL_TAP TRUE
J 2
(575 4375);
DISPLAY 1.234043 (575 4375);
PAINT GREEN (575 4375);
DISPLAY INVISIBLE (575 4375);
FORCEPROP 1 LAST PATH I12
J 2
(900 4500);
DISPLAY 0.936170 (900 4500);
PAINT GREEN (900 4500);
DISPLAY INVISIBLE (900 4500);
FORCEADD TAP..6
(-3200 4300);
FORCEPROP 3 LASTPIN (-3150 4300) SIG_NAME M_M_MA<8>
J 0
(-3140 4310);
DISPLAY 0.659574 (-3140 4310);
PAINT MONO (-3140 4310);
DISPLAY INVISIBLE (-3140 4310);
FORCEPROP 1 LASTPIN (-3150 4300) BN 8
J 0
(-3200 4310);
DISPLAY 0.617021 (-3200 4310);
PAINT PINK (-3200 4310);
FORCEPROP 2 LAST CDS_LIB mstr_standard
J 2
(-3200 4300);
DISPLAY 0.787234 (-3200 4300);
PAINT MONO (-3200 4300);
DISPLAY INVISIBLE (-3200 4300);
FORCEPROP 1 LAST BODY_TYPE PLUMBING
J 0
(-3200 4250);
DISPLAY 1.234043 (-3200 4250);
PAINT GREEN (-3200 4250);
DISPLAY INVISIBLE (-3200 4250);
FORCEPROP 1 LAST HDL_TAP TRUE
J 0
(-2875 4175);
DISPLAY 1.234043 (-2875 4175);
PAINT GREEN (-2875 4175);
DISPLAY INVISIBLE (-2875 4175);
FORCEPROP 1 LAST PATH I120
J 0
(-3200 4300);
DISPLAY 0.936170 (-3200 4300);
PAINT GREEN (-3200 4300);
DISPLAY INVISIBLE (-3200 4300);
FORCEADD TAP..6
(-3200 4350);
FORCEPROP 3 LASTPIN (-3150 4350) SIG_NAME M_M_MA<9>
J 0
(-3140 4360);
DISPLAY 0.659574 (-3140 4360);
PAINT MONO (-3140 4360);
DISPLAY INVISIBLE (-3140 4360);
FORCEPROP 1 LASTPIN (-3150 4350) BN 9
J 0
(-3200 4360);
DISPLAY 0.617021 (-3200 4360);
PAINT PINK (-3200 4360);
FORCEPROP 2 LAST CDS_LIB mstr_standard
J 2
(-3200 4350);
DISPLAY 0.787234 (-3200 4350);
PAINT MONO (-3200 4350);
DISPLAY INVISIBLE (-3200 4350);
FORCEPROP 1 LAST BODY_TYPE PLUMBING
J 0
(-3200 4300);
DISPLAY 1.234043 (-3200 4300);
PAINT GREEN (-3200 4300);
DISPLAY INVISIBLE (-3200 4300);
FORCEPROP 1 LAST HDL_TAP TRUE
J 0
(-2875 4225);
DISPLAY 1.234043 (-2875 4225);
PAINT GREEN (-2875 4225);
DISPLAY INVISIBLE (-2875 4225);
FORCEPROP 1 LAST PATH I121
J 0
(-3200 4350);
DISPLAY 0.936170 (-3200 4350);
PAINT GREEN (-3200 4350);
DISPLAY INVISIBLE (-3200 4350);
FORCEADD TAP..6
(-3200 4250);
FORCEPROP 3 LASTPIN (-3150 4250) SIG_NAME M_M_MA<7>
J 0
(-3140 4260);
DISPLAY 0.659574 (-3140 4260);
PAINT MONO (-3140 4260);
DISPLAY INVISIBLE (-3140 4260);
FORCEPROP 1 LASTPIN (-3150 4250) BN 7
J 0
(-3200 4260);
DISPLAY 0.617021 (-3200 4260);
PAINT PINK (-3200 4260);
FORCEPROP 2 LAST CDS_LIB mstr_standard
J 2
(-3200 4250);
DISPLAY 0.787234 (-3200 4250);
PAINT MONO (-3200 4250);
DISPLAY INVISIBLE (-3200 4250);
FORCEPROP 1 LAST BODY_TYPE PLUMBING
J 0
(-3200 4200);
DISPLAY 1.234043 (-3200 4200);
PAINT GREEN (-3200 4200);
DISPLAY INVISIBLE (-3200 4200);
FORCEPROP 1 LAST HDL_TAP TRUE
J 0
(-2875 4125);
DISPLAY 1.234043 (-2875 4125);
PAINT GREEN (-2875 4125);
DISPLAY INVISIBLE (-2875 4125);
FORCEPROP 1 LAST PATH I122
J 0
(-3200 4250);
DISPLAY 0.936170 (-3200 4250);
PAINT GREEN (-3200 4250);
DISPLAY INVISIBLE (-3200 4250);
FORCEADD TAP..6
(-3200 4200);
FORCEPROP 3 LASTPIN (-3150 4200) SIG_NAME M_M_MA<6>
J 0
(-3140 4210);
DISPLAY 0.659574 (-3140 4210);
PAINT MONO (-3140 4210);
DISPLAY INVISIBLE (-3140 4210);
FORCEPROP 1 LASTPIN (-3150 4200) BN 6
J 0
(-3200 4210);
DISPLAY 0.617021 (-3200 4210);
PAINT PINK (-3200 4210);
FORCEPROP 2 LAST CDS_LIB mstr_standard
J 2
(-3200 4200);
DISPLAY 0.787234 (-3200 4200);
PAINT MONO (-3200 4200);
DISPLAY INVISIBLE (-3200 4200);
FORCEPROP 1 LAST BODY_TYPE PLUMBING
J 0
(-3200 4150);
DISPLAY 1.234043 (-3200 4150);
PAINT GREEN (-3200 4150);
DISPLAY INVISIBLE (-3200 4150);
FORCEPROP 1 LAST HDL_TAP TRUE
J 0
(-2875 4075);
DISPLAY 1.234043 (-2875 4075);
PAINT GREEN (-2875 4075);
DISPLAY INVISIBLE (-2875 4075);
FORCEPROP 1 LAST PATH I123
J 0
(-3200 4200);
DISPLAY 0.936170 (-3200 4200);
PAINT GREEN (-3200 4200);
DISPLAY INVISIBLE (-3200 4200);
FORCEADD TAP..6
(-3200 4150);
FORCEPROP 3 LASTPIN (-3150 4150) SIG_NAME M_M_MA<5>
J 0
(-3140 4160);
DISPLAY 0.659574 (-3140 4160);
PAINT MONO (-3140 4160);
DISPLAY INVISIBLE (-3140 4160);
FORCEPROP 1 LASTPIN (-3150 4150) BN 5
J 0
(-3200 4160);
DISPLAY 0.617021 (-3200 4160);
PAINT PINK (-3200 4160);
FORCEPROP 2 LAST CDS_LIB mstr_standard
J 2
(-3200 4150);
DISPLAY 0.787234 (-3200 4150);
PAINT MONO (-3200 4150);
DISPLAY INVISIBLE (-3200 4150);
FORCEPROP 1 LAST BODY_TYPE PLUMBING
J 0
(-3200 4100);
DISPLAY 1.234043 (-3200 4100);
PAINT GREEN (-3200 4100);
DISPLAY INVISIBLE (-3200 4100);
FORCEPROP 1 LAST HDL_TAP TRUE
J 0
(-2875 4025);
DISPLAY 1.234043 (-2875 4025);
PAINT GREEN (-2875 4025);
DISPLAY INVISIBLE (-2875 4025);
FORCEPROP 1 LAST PATH I124
J 0
(-3200 4150);
DISPLAY 0.936170 (-3200 4150);
PAINT GREEN (-3200 4150);
DISPLAY INVISIBLE (-3200 4150);
FORCEADD TAP..6
(-3200 4100);
FORCEPROP 3 LASTPIN (-3150 4100) SIG_NAME M_M_MA<4>
J 0
(-3140 4110);
DISPLAY 0.659574 (-3140 4110);
PAINT MONO (-3140 4110);
DISPLAY INVISIBLE (-3140 4110);
FORCEPROP 1 LASTPIN (-3150 4100) BN 4
J 0
(-3200 4110);
DISPLAY 0.617021 (-3200 4110);
PAINT PINK (-3200 4110);
FORCEPROP 2 LAST CDS_LIB mstr_standard
J 2
(-3200 4100);
DISPLAY 0.787234 (-3200 4100);
PAINT MONO (-3200 4100);
DISPLAY INVISIBLE (-3200 4100);
FORCEPROP 1 LAST BODY_TYPE PLUMBING
J 0
(-3200 4050);
DISPLAY 1.234043 (-3200 4050);
PAINT GREEN (-3200 4050);
DISPLAY INVISIBLE (-3200 4050);
FORCEPROP 1 LAST HDL_TAP TRUE
J 0
(-2875 3975);
DISPLAY 1.234043 (-2875 3975);
PAINT GREEN (-2875 3975);
DISPLAY INVISIBLE (-2875 3975);
FORCEPROP 1 LAST PATH I125
J 0
(-3200 4100);
DISPLAY 0.936170 (-3200 4100);
PAINT GREEN (-3200 4100);
DISPLAY INVISIBLE (-3200 4100);
FORCEADD TAP..6
(-3200 4050);
FORCEPROP 3 LASTPIN (-3150 4050) SIG_NAME M_M_MA<3>
J 0
(-3140 4060);
DISPLAY 0.659574 (-3140 4060);
PAINT MONO (-3140 4060);
DISPLAY INVISIBLE (-3140 4060);
FORCEPROP 1 LASTPIN (-3150 4050) BN 3
J 0
(-3200 4060);
DISPLAY 0.617021 (-3200 4060);
PAINT PINK (-3200 4060);
FORCEPROP 2 LAST CDS_LIB mstr_standard
J 2
(-3200 4050);
DISPLAY 0.787234 (-3200 4050);
PAINT MONO (-3200 4050);
DISPLAY INVISIBLE (-3200 4050);
FORCEPROP 1 LAST BODY_TYPE PLUMBING
J 0
(-3200 4000);
DISPLAY 1.234043 (-3200 4000);
PAINT GREEN (-3200 4000);
DISPLAY INVISIBLE (-3200 4000);
FORCEPROP 1 LAST HDL_TAP TRUE
J 0
(-2875 3925);
DISPLAY 1.234043 (-2875 3925);
PAINT GREEN (-2875 3925);
DISPLAY INVISIBLE (-2875 3925);
FORCEPROP 1 LAST PATH I126
J 0
(-3200 4050);
DISPLAY 0.936170 (-3200 4050);
PAINT GREEN (-3200 4050);
DISPLAY INVISIBLE (-3200 4050);
FORCEADD TAP..6
(-3200 4000);
FORCEPROP 3 LASTPIN (-3150 4000) SIG_NAME M_M_MA<2>
J 0
(-3140 4010);
DISPLAY 0.659574 (-3140 4010);
PAINT MONO (-3140 4010);
DISPLAY INVISIBLE (-3140 4010);
FORCEPROP 1 LASTPIN (-3150 4000) BN 2
J 0
(-3200 4010);
DISPLAY 0.617021 (-3200 4010);
PAINT PINK (-3200 4010);
FORCEPROP 2 LAST CDS_LIB mstr_standard
J 2
(-3200 4000);
DISPLAY 0.787234 (-3200 4000);
PAINT MONO (-3200 4000);
DISPLAY INVISIBLE (-3200 4000);
FORCEPROP 1 LAST BODY_TYPE PLUMBING
J 0
(-3200 3950);
DISPLAY 1.234043 (-3200 3950);
PAINT GREEN (-3200 3950);
DISPLAY INVISIBLE (-3200 3950);
FORCEPROP 1 LAST HDL_TAP TRUE
J 0
(-2875 3875);
DISPLAY 1.234043 (-2875 3875);
PAINT GREEN (-2875 3875);
DISPLAY INVISIBLE (-2875 3875);
FORCEPROP 1 LAST PATH I127
J 0
(-3200 4000);
DISPLAY 0.936170 (-3200 4000);
PAINT GREEN (-3200 4000);
DISPLAY INVISIBLE (-3200 4000);
FORCEADD TAP..6
(-3200 3950);
FORCEPROP 3 LASTPIN (-3150 3950) SIG_NAME M_M_MA<1>
J 0
(-3140 3960);
DISPLAY 0.659574 (-3140 3960);
PAINT MONO (-3140 3960);
DISPLAY INVISIBLE (-3140 3960);
FORCEPROP 1 LASTPIN (-3150 3950) BN 1
J 0
(-3200 3960);
DISPLAY 0.617021 (-3200 3960);
PAINT PINK (-3200 3960);
FORCEPROP 2 LAST CDS_LIB mstr_standard
J 2
(-3200 3950);
DISPLAY 0.787234 (-3200 3950);
PAINT MONO (-3200 3950);
DISPLAY INVISIBLE (-3200 3950);
FORCEPROP 1 LAST BODY_TYPE PLUMBING
J 0
(-3200 3900);
DISPLAY 1.234043 (-3200 3900);
PAINT GREEN (-3200 3900);
DISPLAY INVISIBLE (-3200 3900);
FORCEPROP 1 LAST HDL_TAP TRUE
J 0
(-2875 3825);
DISPLAY 1.234043 (-2875 3825);
PAINT GREEN (-2875 3825);
DISPLAY INVISIBLE (-2875 3825);
FORCEPROP 1 LAST PATH I128
J 0
(-3200 3950);
DISPLAY 0.936170 (-3200 3950);
PAINT GREEN (-3200 3950);
DISPLAY INVISIBLE (-3200 3950);
FORCEADD TAP..6
(-3200 3900);
FORCEPROP 3 LASTPIN (-3150 3900) SIG_NAME M_M_MA<0>
J 0
(-3140 3910);
DISPLAY 0.659574 (-3140 3910);
PAINT MONO (-3140 3910);
DISPLAY INVISIBLE (-3140 3910);
FORCEPROP 1 LASTPIN (-3150 3900) BN 0
J 0
(-3200 3910);
DISPLAY 0.617021 (-3200 3910);
PAINT PINK (-3200 3910);
FORCEPROP 2 LAST CDS_LIB mstr_standard
J 2
(-3200 3900);
DISPLAY 0.787234 (-3200 3900);
PAINT MONO (-3200 3900);
DISPLAY INVISIBLE (-3200 3900);
FORCEPROP 1 LAST BODY_TYPE PLUMBING
J 0
(-3200 3850);
DISPLAY 1.234043 (-3200 3850);
PAINT GREEN (-3200 3850);
DISPLAY INVISIBLE (-3200 3850);
FORCEPROP 1 LAST HDL_TAP TRUE
J 0
(-2875 3775);
DISPLAY 1.234043 (-2875 3775);
PAINT GREEN (-2875 3775);
DISPLAY INVISIBLE (-2875 3775);
FORCEPROP 1 LAST PATH I129
J 0
(-3200 3900);
DISPLAY 0.936170 (-3200 3900);
PAINT GREEN (-3200 3900);
DISPLAY INVISIBLE (-3200 3900);
FORCEADD TAP..6
R 2
(900 4400);
FORCEPROP 3 LASTPIN (850 4400) SIG_NAME M_M_DQS_DN<10>
J 0
(860 4410);
DISPLAY 0.659574 (860 4410);
PAINT MONO (860 4410);
DISPLAY INVISIBLE (860 4410);
FORCEPROP 1 LASTPIN (850 4400) BN 10
J 2
(900 4410);
DISPLAY 0.617021 (900 4410);
PAINT PINK (900 4410);
FORCEPROP 2 LAST CDS_LIB mstr_standard
J 0
(900 4400);
DISPLAY 0.787234 (900 4400);
PAINT MONO (900 4400);
DISPLAY INVISIBLE (900 4400);
FORCEPROP 1 LAST BODY_TYPE PLUMBING
J 2
(900 4350);
DISPLAY 1.234043 (900 4350);
PAINT GREEN (900 4350);
DISPLAY INVISIBLE (900 4350);
FORCEPROP 1 LAST HDL_TAP TRUE
J 2
(575 4275);
DISPLAY 1.234043 (575 4275);
PAINT GREEN (575 4275);
DISPLAY INVISIBLE (575 4275);
FORCEPROP 1 LAST PATH I13
J 2
(900 4400);
DISPLAY 0.936170 (900 4400);
PAINT GREEN (900 4400);
DISPLAY INVISIBLE (900 4400);
FORCEADD TAP..6
(-3200 3800);
FORCEPROP 3 LASTPIN (-3150 3800) SIG_NAME M_M_BA<1>
J 0
(-3140 3810);
DISPLAY 0.659574 (-3140 3810);
PAINT MONO (-3140 3810);
DISPLAY INVISIBLE (-3140 3810);
FORCEPROP 1 LASTPIN (-3150 3800) BN 1
J 0
(-3200 3810);
DISPLAY 0.617021 (-3200 3810);
PAINT PINK (-3200 3810);
FORCEPROP 2 LAST CDS_LIB mstr_standard
J 0
(-3200 3800);
DISPLAY 0.787234 (-3200 3800);
PAINT MONO (-3200 3800);
DISPLAY INVISIBLE (-3200 3800);
FORCEPROP 1 LAST BODY_TYPE PLUMBING
J 0
(-3200 3750);
DISPLAY 1.234043 (-3200 3750);
PAINT GREEN (-3200 3750);
DISPLAY INVISIBLE (-3200 3750);
FORCEPROP 1 LAST HDL_TAP TRUE
J 0
(-2875 3675);
DISPLAY 1.234043 (-2875 3675);
PAINT GREEN (-2875 3675);
DISPLAY INVISIBLE (-2875 3675);
FORCEPROP 1 LAST PATH I130
J 0
(-3200 3800);
DISPLAY 0.936170 (-3200 3800);
PAINT GREEN (-3200 3800);
DISPLAY INVISIBLE (-3200 3800);
FORCEADD OFFPAGE..1
(-3800 4800);
FORCEPROP 2 LAST $XR1 87 
J 0
(-4141 4800);
DISPLAY 0.638298 (-4141 4800);
PAINT MONO (-4141 4800);
FORCEPROP 2 LAST $XR0 62 
J 0
(-4051 4800);
DISPLAY 0.638298 (-4051 4800);
PAINT MONO (-4051 4800);
FORCEPROP 2 LAST CDS_LIB mstr_standard
J 0
(-3800 4800);
DISPLAY 0.787234 (-3800 4800);
PAINT MONO (-3800 4800);
DISPLAY INVISIBLE (-3800 4800);
FORCEPROP 1 LAST OFFPAGE TRUE
J 0
(-3475 4675);
DISPLAY 0.936170 (-3475 4675);
PAINT GREEN (-3475 4675);
DISPLAY INVISIBLE (-3475 4675);
FORCEPROP 1 LAST COMMENT_BODY TRUE
J 0
(-3675 4700);
DISPLAY 0.936170 (-3675 4700);
PAINT GREEN (-3675 4700);
DISPLAY INVISIBLE (-3675 4700);
FORCEPROP 2 LAST PATH I131
J 0
(-3750 4875);
DISPLAY 0.787234 (-3750 4875);
PAINT MONO (-3750 4875);
DISPLAY INVISIBLE (-3750 4875);
FORCEADD OFFPAGE..1
(-3800 3850);
FORCEPROP 2 LAST $XR1 87 
J 0
(-4141 3850);
DISPLAY 0.638298 (-4141 3850);
PAINT MONO (-4141 3850);
FORCEPROP 2 LAST $XR0 62 
J 0
(-4051 3850);
DISPLAY 0.638298 (-4051 3850);
PAINT MONO (-4051 3850);
FORCEPROP 2 LAST CDS_LIB mstr_standard
J 0
(-3800 3850);
DISPLAY 0.787234 (-3800 3850);
PAINT MONO (-3800 3850);
DISPLAY INVISIBLE (-3800 3850);
FORCEPROP 1 LAST OFFPAGE TRUE
J 0
(-3475 3725);
DISPLAY 0.936170 (-3475 3725);
PAINT GREEN (-3475 3725);
DISPLAY INVISIBLE (-3475 3725);
FORCEPROP 1 LAST COMMENT_BODY TRUE
J 0
(-3675 3750);
DISPLAY 0.936170 (-3675 3750);
PAINT GREEN (-3675 3750);
DISPLAY INVISIBLE (-3675 3750);
FORCEPROP 2 LAST PATH I132
J 0
(-3750 3925);
DISPLAY 0.787234 (-3750 3925);
PAINT MONO (-3750 3925);
DISPLAY INVISIBLE (-3750 3925);
FORCEADD TAP..6
(-3200 3750);
FORCEPROP 3 LASTPIN (-3150 3750) SIG_NAME M_M_BA<0>
J 0
(-3140 3760);
DISPLAY 0.659574 (-3140 3760);
PAINT MONO (-3140 3760);
DISPLAY INVISIBLE (-3140 3760);
FORCEPROP 1 LASTPIN (-3150 3750) BN 0
J 0
(-3200 3760);
DISPLAY 0.617021 (-3200 3760);
PAINT PINK (-3200 3760);
FORCEPROP 2 LAST CDS_LIB mstr_standard
J 0
(-3200 3750);
DISPLAY 0.787234 (-3200 3750);
PAINT MONO (-3200 3750);
DISPLAY INVISIBLE (-3200 3750);
FORCEPROP 1 LAST BODY_TYPE PLUMBING
J 0
(-3200 3700);
DISPLAY 1.234043 (-3200 3700);
PAINT GREEN (-3200 3700);
DISPLAY INVISIBLE (-3200 3700);
FORCEPROP 1 LAST HDL_TAP TRUE
J 0
(-2875 3625);
DISPLAY 1.234043 (-2875 3625);
PAINT GREEN (-2875 3625);
DISPLAY INVISIBLE (-2875 3625);
FORCEPROP 1 LAST PATH I133
J 0
(-3200 3750);
DISPLAY 0.936170 (-3200 3750);
PAINT GREEN (-3200 3750);
DISPLAY INVISIBLE (-3200 3750);
FORCEADD TAP..6
(-3200 3650);
FORCEPROP 3 LASTPIN (-3150 3650) SIG_NAME M_M_BG<0>
J 0
(-3140 3660);
DISPLAY 0.659574 (-3140 3660);
PAINT MONO (-3140 3660);
DISPLAY INVISIBLE (-3140 3660);
FORCEPROP 1 LASTPIN (-3150 3650) BN 0
J 0
(-3200 3660);
DISPLAY 0.617021 (-3200 3660);
PAINT PINK (-3200 3660);
FORCEPROP 2 LAST CDS_LIB mstr_standard
J 0
(-3200 3650);
DISPLAY 0.787234 (-3200 3650);
PAINT MONO (-3200 3650);
DISPLAY INVISIBLE (-3200 3650);
FORCEPROP 1 LAST BODY_TYPE PLUMBING
J 0
(-3200 3600);
DISPLAY 1.234043 (-3200 3600);
PAINT GREEN (-3200 3600);
DISPLAY INVISIBLE (-3200 3600);
FORCEPROP 1 LAST HDL_TAP TRUE
J 0
(-2875 3525);
DISPLAY 1.234043 (-2875 3525);
PAINT GREEN (-2875 3525);
DISPLAY INVISIBLE (-2875 3525);
FORCEPROP 1 LAST PATH I134
J 0
(-3200 3650);
DISPLAY 0.936170 (-3200 3650);
PAINT GREEN (-3200 3650);
DISPLAY INVISIBLE (-3200 3650);
FORCEADD TAP..6
(-3200 3700);
FORCEPROP 3 LASTPIN (-3150 3700) SIG_NAME M_M_BG<1>
J 0
(-3140 3710);
DISPLAY 0.659574 (-3140 3710);
PAINT MONO (-3140 3710);
DISPLAY INVISIBLE (-3140 3710);
FORCEPROP 1 LASTPIN (-3150 3700) BN 1
J 0
(-3200 3710);
DISPLAY 0.617021 (-3200 3710);
PAINT PINK (-3200 3710);
FORCEPROP 2 LAST CDS_LIB mstr_standard
J 0
(-3200 3700);
DISPLAY 0.787234 (-3200 3700);
PAINT MONO (-3200 3700);
DISPLAY INVISIBLE (-3200 3700);
FORCEPROP 1 LAST BODY_TYPE PLUMBING
J 0
(-3200 3650);
DISPLAY 1.234043 (-3200 3650);
PAINT GREEN (-3200 3650);
DISPLAY INVISIBLE (-3200 3650);
FORCEPROP 1 LAST HDL_TAP TRUE
J 0
(-2875 3575);
DISPLAY 1.234043 (-2875 3575);
PAINT GREEN (-2875 3575);
DISPLAY INVISIBLE (-2875 3575);
FORCEPROP 1 LAST PATH I135
J 0
(-3200 3700);
DISPLAY 0.936170 (-3200 3700);
PAINT GREEN (-3200 3700);
DISPLAY INVISIBLE (-3200 3700);
FORCEADD OFFPAGE..1
(-3800 3325);
FORCEPROP 2 LAST $XR1 87 
J 0
(-4141 3325);
DISPLAY 0.638298 (-4141 3325);
PAINT MONO (-4141 3325);
FORCEPROP 2 LAST $XR0 62 
J 0
(-4051 3325);
DISPLAY 0.638298 (-4051 3325);
PAINT MONO (-4051 3325);
FORCEPROP 2 LAST CDS_LIB mstr_standard
J 0
(-3800 3325);
DISPLAY 0.787234 (-3800 3325);
PAINT MONO (-3800 3325);
DISPLAY INVISIBLE (-3800 3325);
FORCEPROP 1 LAST OFFPAGE TRUE
J 0
(-3475 3200);
DISPLAY 0.936170 (-3475 3200);
PAINT GREEN (-3475 3200);
DISPLAY INVISIBLE (-3475 3200);
FORCEPROP 1 LAST COMMENT_BODY TRUE
J 0
(-3675 3225);
DISPLAY 0.936170 (-3675 3225);
PAINT GREEN (-3675 3225);
DISPLAY INVISIBLE (-3675 3225);
FORCEPROP 2 LAST PATH I136
J 0
(-3750 3400);
DISPLAY 0.787234 (-3750 3400);
PAINT MONO (-3750 3400);
DISPLAY INVISIBLE (-3750 3400);
FORCEADD OFFPAGE..1
(-3800 3750);
FORCEPROP 2 LAST $XR1 87 
J 0
(-4141 3750);
DISPLAY 0.638298 (-4141 3750);
PAINT MONO (-4141 3750);
FORCEPROP 2 LAST $XR0 62 
J 0
(-4051 3750);
DISPLAY 0.638298 (-4051 3750);
PAINT MONO (-4051 3750);
FORCEPROP 2 LAST CDS_LIB mstr_standard
J 0
(-3800 3750);
DISPLAY 0.787234 (-3800 3750);
PAINT MONO (-3800 3750);
DISPLAY INVISIBLE (-3800 3750);
FORCEPROP 1 LAST OFFPAGE TRUE
J 0
(-3475 3625);
DISPLAY 0.936170 (-3475 3625);
PAINT GREEN (-3475 3625);
DISPLAY INVISIBLE (-3475 3625);
FORCEPROP 1 LAST COMMENT_BODY TRUE
J 0
(-3675 3650);
DISPLAY 0.936170 (-3675 3650);
PAINT GREEN (-3675 3650);
DISPLAY INVISIBLE (-3675 3650);
FORCEPROP 2 LAST PATH I137
J 0
(-3750 3825);
DISPLAY 0.787234 (-3750 3825);
PAINT MONO (-3750 3825);
DISPLAY INVISIBLE (-3750 3825);
FORCEADD TAP..6
(-3200 2650);
FORCEPROP 3 LASTPIN (-3150 2650) SIG_NAME M_M_ECC<6>
J 0
(-3140 2660);
DISPLAY 0.659574 (-3140 2660);
PAINT MONO (-3140 2660);
DISPLAY INVISIBLE (-3140 2660);
FORCEPROP 1 LASTPIN (-3150 2650) BN 6
J 0
(-3200 2660);
DISPLAY 0.617021 (-3200 2660);
PAINT PINK (-3200 2660);
FORCEPROP 2 LAST CDS_LIB mstr_standard
J 0
(-3200 2650);
DISPLAY 0.787234 (-3200 2650);
PAINT MONO (-3200 2650);
DISPLAY INVISIBLE (-3200 2650);
FORCEPROP 1 LAST BODY_TYPE PLUMBING
J 0
(-3200 2600);
DISPLAY 1.234043 (-3200 2600);
PAINT GREEN (-3200 2600);
DISPLAY INVISIBLE (-3200 2600);
FORCEPROP 1 LAST HDL_TAP TRUE
J 0
(-2875 2525);
DISPLAY 1.234043 (-2875 2525);
PAINT GREEN (-2875 2525);
DISPLAY INVISIBLE (-2875 2525);
FORCEPROP 1 LAST PATH I138
J 0
(-3200 2650);
DISPLAY 0.936170 (-3200 2650);
PAINT GREEN (-3200 2650);
DISPLAY INVISIBLE (-3200 2650);
FORCEADD TAP..6
(-3200 2700);
FORCEPROP 3 LASTPIN (-3150 2700) SIG_NAME M_M_ECC<7>
J 0
(-3140 2710);
DISPLAY 0.659574 (-3140 2710);
PAINT MONO (-3140 2710);
DISPLAY INVISIBLE (-3140 2710);
FORCEPROP 1 LASTPIN (-3150 2700) BN 7
J 0
(-3200 2710);
DISPLAY 0.617021 (-3200 2710);
PAINT PINK (-3200 2710);
FORCEPROP 2 LAST CDS_LIB mstr_standard
J 0
(-3200 2700);
DISPLAY 0.787234 (-3200 2700);
PAINT MONO (-3200 2700);
DISPLAY INVISIBLE (-3200 2700);
FORCEPROP 1 LAST BODY_TYPE PLUMBING
J 0
(-3200 2650);
DISPLAY 1.234043 (-3200 2650);
PAINT GREEN (-3200 2650);
DISPLAY INVISIBLE (-3200 2650);
FORCEPROP 1 LAST HDL_TAP TRUE
J 0
(-2875 2575);
DISPLAY 1.234043 (-2875 2575);
PAINT GREEN (-2875 2575);
DISPLAY INVISIBLE (-2875 2575);
FORCEPROP 1 LAST PATH I139
J 0
(-3200 2700);
DISPLAY 0.936170 (-3200 2700);
PAINT GREEN (-3200 2700);
DISPLAY INVISIBLE (-3200 2700);
FORCEADD TAP..6
R 2
(900 4300);
FORCEPROP 3 LASTPIN (850 4300) SIG_NAME M_M_DQS_DN<9>
J 0
(860 4310);
DISPLAY 0.659574 (860 4310);
PAINT MONO (860 4310);
DISPLAY INVISIBLE (860 4310);
FORCEPROP 1 LASTPIN (850 4300) BN 9
J 2
(900 4310);
DISPLAY 0.617021 (900 4310);
PAINT PINK (900 4310);
FORCEPROP 2 LAST CDS_LIB mstr_standard
J 0
(900 4300);
DISPLAY 0.787234 (900 4300);
PAINT MONO (900 4300);
DISPLAY INVISIBLE (900 4300);
FORCEPROP 1 LAST BODY_TYPE PLUMBING
J 2
(900 4250);
DISPLAY 1.234043 (900 4250);
PAINT GREEN (900 4250);
DISPLAY INVISIBLE (900 4250);
FORCEPROP 1 LAST HDL_TAP TRUE
J 2
(575 4175);
DISPLAY 1.234043 (575 4175);
PAINT GREEN (575 4175);
DISPLAY INVISIBLE (575 4175);
FORCEPROP 1 LAST PATH I14
J 2
(900 4300);
DISPLAY 0.936170 (900 4300);
PAINT GREEN (900 4300);
DISPLAY INVISIBLE (900 4300);
FORCEADD TAP..6
(-3200 2600);
FORCEPROP 3 LASTPIN (-3150 2600) SIG_NAME M_M_ECC<5>
J 0
(-3140 2610);
DISPLAY 0.659574 (-3140 2610);
PAINT MONO (-3140 2610);
DISPLAY INVISIBLE (-3140 2610);
FORCEPROP 1 LASTPIN (-3150 2600) BN 5
J 0
(-3200 2610);
DISPLAY 0.617021 (-3200 2610);
PAINT PINK (-3200 2610);
FORCEPROP 2 LAST CDS_LIB mstr_standard
J 0
(-3200 2600);
DISPLAY 0.787234 (-3200 2600);
PAINT MONO (-3200 2600);
DISPLAY INVISIBLE (-3200 2600);
FORCEPROP 1 LAST BODY_TYPE PLUMBING
J 0
(-3200 2550);
DISPLAY 1.234043 (-3200 2550);
PAINT GREEN (-3200 2550);
DISPLAY INVISIBLE (-3200 2550);
FORCEPROP 1 LAST HDL_TAP TRUE
J 0
(-2875 2475);
DISPLAY 1.234043 (-2875 2475);
PAINT GREEN (-2875 2475);
DISPLAY INVISIBLE (-2875 2475);
FORCEPROP 1 LAST PATH I140
J 0
(-3200 2600);
DISPLAY 0.936170 (-3200 2600);
PAINT GREEN (-3200 2600);
DISPLAY INVISIBLE (-3200 2600);
FORCEADD TAP..6
(-3200 2550);
FORCEPROP 3 LASTPIN (-3150 2550) SIG_NAME M_M_ECC<4>
J 0
(-3140 2560);
DISPLAY 0.659574 (-3140 2560);
PAINT MONO (-3140 2560);
DISPLAY INVISIBLE (-3140 2560);
FORCEPROP 1 LASTPIN (-3150 2550) BN 4
J 0
(-3200 2560);
DISPLAY 0.617021 (-3200 2560);
PAINT PINK (-3200 2560);
FORCEPROP 2 LAST CDS_LIB mstr_standard
J 0
(-3200 2550);
DISPLAY 0.787234 (-3200 2550);
PAINT MONO (-3200 2550);
DISPLAY INVISIBLE (-3200 2550);
FORCEPROP 1 LAST BODY_TYPE PLUMBING
J 0
(-3200 2500);
DISPLAY 1.234043 (-3200 2500);
PAINT GREEN (-3200 2500);
DISPLAY INVISIBLE (-3200 2500);
FORCEPROP 1 LAST HDL_TAP TRUE
J 0
(-2875 2425);
DISPLAY 1.234043 (-2875 2425);
PAINT GREEN (-2875 2425);
DISPLAY INVISIBLE (-2875 2425);
FORCEPROP 1 LAST PATH I141
J 0
(-3200 2550);
DISPLAY 0.936170 (-3200 2550);
PAINT GREEN (-3200 2550);
DISPLAY INVISIBLE (-3200 2550);
FORCEADD TAP..6
(-3200 2500);
FORCEPROP 3 LASTPIN (-3150 2500) SIG_NAME M_M_ECC<3>
J 0
(-3140 2510);
DISPLAY 0.659574 (-3140 2510);
PAINT MONO (-3140 2510);
DISPLAY INVISIBLE (-3140 2510);
FORCEPROP 1 LASTPIN (-3150 2500) BN 3
J 0
(-3200 2510);
DISPLAY 0.617021 (-3200 2510);
PAINT PINK (-3200 2510);
FORCEPROP 2 LAST CDS_LIB mstr_standard
J 0
(-3200 2500);
DISPLAY 0.787234 (-3200 2500);
PAINT MONO (-3200 2500);
DISPLAY INVISIBLE (-3200 2500);
FORCEPROP 1 LAST BODY_TYPE PLUMBING
J 0
(-3200 2450);
DISPLAY 1.234043 (-3200 2450);
PAINT GREEN (-3200 2450);
DISPLAY INVISIBLE (-3200 2450);
FORCEPROP 1 LAST HDL_TAP TRUE
J 0
(-2875 2375);
DISPLAY 1.234043 (-2875 2375);
PAINT GREEN (-2875 2375);
DISPLAY INVISIBLE (-2875 2375);
FORCEPROP 1 LAST PATH I142
J 0
(-3200 2500);
DISPLAY 0.936170 (-3200 2500);
PAINT GREEN (-3200 2500);
DISPLAY INVISIBLE (-3200 2500);
FORCEADD TAP..6
(-3200 2450);
FORCEPROP 3 LASTPIN (-3150 2450) SIG_NAME M_M_ECC<2>
J 0
(-3140 2460);
DISPLAY 0.659574 (-3140 2460);
PAINT MONO (-3140 2460);
DISPLAY INVISIBLE (-3140 2460);
FORCEPROP 1 LASTPIN (-3150 2450) BN 2
J 0
(-3200 2460);
DISPLAY 0.617021 (-3200 2460);
PAINT PINK (-3200 2460);
FORCEPROP 2 LAST CDS_LIB mstr_standard
J 0
(-3200 2450);
DISPLAY 0.787234 (-3200 2450);
PAINT MONO (-3200 2450);
DISPLAY INVISIBLE (-3200 2450);
FORCEPROP 1 LAST BODY_TYPE PLUMBING
J 0
(-3200 2400);
DISPLAY 1.234043 (-3200 2400);
PAINT GREEN (-3200 2400);
DISPLAY INVISIBLE (-3200 2400);
FORCEPROP 1 LAST HDL_TAP TRUE
J 0
(-2875 2325);
DISPLAY 1.234043 (-2875 2325);
PAINT GREEN (-2875 2325);
DISPLAY INVISIBLE (-2875 2325);
FORCEPROP 1 LAST PATH I143
J 0
(-3200 2450);
DISPLAY 0.936170 (-3200 2450);
PAINT GREEN (-3200 2450);
DISPLAY INVISIBLE (-3200 2450);
FORCEADD TAP..6
(-3200 2400);
FORCEPROP 3 LASTPIN (-3150 2400) SIG_NAME M_M_ECC<1>
J 0
(-3140 2410);
DISPLAY 0.659574 (-3140 2410);
PAINT MONO (-3140 2410);
DISPLAY INVISIBLE (-3140 2410);
FORCEPROP 1 LASTPIN (-3150 2400) BN 1
J 0
(-3200 2410);
DISPLAY 0.617021 (-3200 2410);
PAINT PINK (-3200 2410);
FORCEPROP 2 LAST CDS_LIB mstr_standard
J 0
(-3200 2400);
DISPLAY 0.787234 (-3200 2400);
PAINT MONO (-3200 2400);
DISPLAY INVISIBLE (-3200 2400);
FORCEPROP 1 LAST BODY_TYPE PLUMBING
J 0
(-3200 2350);
DISPLAY 1.234043 (-3200 2350);
PAINT GREEN (-3200 2350);
DISPLAY INVISIBLE (-3200 2350);
FORCEPROP 1 LAST HDL_TAP TRUE
J 0
(-2875 2275);
DISPLAY 1.234043 (-2875 2275);
PAINT GREEN (-2875 2275);
DISPLAY INVISIBLE (-2875 2275);
FORCEPROP 1 LAST PATH I144
J 0
(-3200 2400);
DISPLAY 0.936170 (-3200 2400);
PAINT GREEN (-3200 2400);
DISPLAY INVISIBLE (-3200 2400);
FORCEADD TAP..6
(-3200 2350);
FORCEPROP 3 LASTPIN (-3150 2350) SIG_NAME M_M_ECC<0>
J 0
(-3140 2360);
DISPLAY 0.659574 (-3140 2360);
PAINT MONO (-3140 2360);
DISPLAY INVISIBLE (-3140 2360);
FORCEPROP 1 LASTPIN (-3150 2350) BN 0
J 0
(-3200 2360);
DISPLAY 0.617021 (-3200 2360);
PAINT PINK (-3200 2360);
FORCEPROP 2 LAST CDS_LIB mstr_standard
J 0
(-3200 2350);
DISPLAY 0.787234 (-3200 2350);
PAINT MONO (-3200 2350);
DISPLAY INVISIBLE (-3200 2350);
FORCEPROP 1 LAST BODY_TYPE PLUMBING
J 0
(-3200 2300);
DISPLAY 1.234043 (-3200 2300);
PAINT GREEN (-3200 2300);
DISPLAY INVISIBLE (-3200 2300);
FORCEPROP 1 LAST HDL_TAP TRUE
J 0
(-2875 2225);
DISPLAY 1.234043 (-2875 2225);
PAINT GREEN (-2875 2225);
DISPLAY INVISIBLE (-2875 2225);
FORCEPROP 1 LAST PATH I145
J 0
(-3200 2350);
DISPLAY 0.936170 (-3200 2350);
PAINT GREEN (-3200 2350);
DISPLAY INVISIBLE (-3200 2350);
FORCEADD OFFPAGE..1
(-3800 2700);
FORCEPROP 2 LAST $XR1 87 
J 0
(-4141 2700);
DISPLAY 0.638298 (-4141 2700);
PAINT MONO (-4141 2700);
FORCEPROP 2 LAST $XR0 62 
J 0
(-4051 2700);
DISPLAY 0.638298 (-4051 2700);
PAINT MONO (-4051 2700);
FORCEPROP 2 LAST CDS_LIB mstr_standard
J 0
(-3800 2700);
DISPLAY 0.787234 (-3800 2700);
PAINT MONO (-3800 2700);
DISPLAY INVISIBLE (-3800 2700);
FORCEPROP 1 LAST OFFPAGE TRUE
J 0
(-3475 2575);
DISPLAY 0.936170 (-3475 2575);
PAINT GREEN (-3475 2575);
DISPLAY INVISIBLE (-3475 2575);
FORCEPROP 1 LAST COMMENT_BODY TRUE
J 0
(-3675 2600);
DISPLAY 0.936170 (-3675 2600);
PAINT GREEN (-3675 2600);
DISPLAY INVISIBLE (-3675 2600);
FORCEPROP 2 LAST PATH I146
J 0
(-3750 2775);
DISPLAY 0.787234 (-3750 2775);
PAINT MONO (-3750 2775);
DISPLAY INVISIBLE (-3750 2775);
FORCEADD OFFPAGE..1
(-3800 2650);
FORCEPROP 2 LAST $XR5 87 
J 0
(-4501 2650);
DISPLAY 0.638298 (-4501 2650);
PAINT MONO (-4501 2650);
FORCEPROP 2 LAST $XR4 86 
J 0
(-4411 2650);
DISPLAY 0.638298 (-4411 2650);
PAINT MONO (-4411 2650);
FORCEPROP 2 LAST $XR3 85 
J 0
(-4321 2650);
DISPLAY 0.638298 (-4321 2650);
PAINT MONO (-4321 2650);
FORCEPROP 2 LAST $XR2 84 
J 0
(-4231 2650);
DISPLAY 0.638298 (-4231 2650);
PAINT MONO (-4231 2650);
FORCEPROP 2 LAST $XR1 83 
J 0
(-4141 2650);
DISPLAY 0.638298 (-4141 2650);
PAINT MONO (-4141 2650);
FORCEPROP 2 LAST $XR0 55 
J 0
(-4051 2650);
DISPLAY 0.638298 (-4051 2650);
PAINT MONO (-4051 2650);
FORCEPROP 2 LAST CDS_LIB mstr_standard
J 0
(-3800 2650);
DISPLAY 0.787234 (-3800 2650);
PAINT MONO (-3800 2650);
DISPLAY INVISIBLE (-3800 2650);
FORCEPROP 1 LAST OFFPAGE TRUE
J 0
(-3475 2525);
DISPLAY 0.936170 (-3475 2525);
PAINT GREEN (-3475 2525);
DISPLAY INVISIBLE (-3475 2525);
FORCEPROP 1 LAST COMMENT_BODY TRUE
J 0
(-3675 2550);
DISPLAY 0.936170 (-3675 2550);
PAINT GREEN (-3675 2550);
DISPLAY INVISIBLE (-3675 2550);
FORCEPROP 2 LAST PATH I147
J 0
(-3750 2725);
DISPLAY 0.787234 (-3750 2725);
PAINT MONO (-3750 2725);
DISPLAY INVISIBLE (-3750 2725);
FORCEADD OFFPAGE..5
(-4025 2100);
FORCEPROP 2 LAST $XR1 62 
J 0
(-4339 2100);
DISPLAY 0.638298 (-4339 2100);
PAINT MONO (-4339 2100);
FORCEPROP 2 LAST $XR0 87 
J 0
(-4249 2100);
DISPLAY 0.638298 (-4249 2100);
PAINT MONO (-4249 2100);
FORCEPROP 2 LAST CDS_LIB mstr_standard
J 0
(-4025 2100);
DISPLAY 0.787234 (-4025 2100);
PAINT MONO (-4025 2100);
DISPLAY INVISIBLE (-4025 2100);
FORCEPROP 1 LAST OFFPAGE TRUE
J 0
(-3700 1975);
DISPLAY 1.404255 (-3700 1975);
PAINT GREEN (-3700 1975);
DISPLAY INVISIBLE (-3700 1975);
FORCEPROP 1 LAST COMMENT_BODY TRUE
J 0
(-3925 2025);
DISPLAY 1.404255 (-3925 2025);
PAINT GREEN (-3925 2025);
DISPLAY INVISIBLE (-3925 2025);
FORCEPROP 2 LAST PATH I148
J 0
(-3975 2175);
DISPLAY 0.787234 (-3975 2175);
PAINT MONO (-3975 2175);
DISPLAY INVISIBLE (-3975 2175);
FORCEADD OFFPAGE..1
(-4000 2050);
FORCEPROP 2 LAST $XR1 87 
J 0
(-4341 2050);
DISPLAY 0.638298 (-4341 2050);
PAINT MONO (-4341 2050);
FORCEPROP 2 LAST $XR0 62 
J 0
(-4251 2050);
DISPLAY 0.638298 (-4251 2050);
PAINT MONO (-4251 2050);
FORCEPROP 2 LAST CDS_LIB mstr_standard
J 0
(-4000 2050);
DISPLAY 0.787234 (-4000 2050);
PAINT MONO (-4000 2050);
DISPLAY INVISIBLE (-4000 2050);
FORCEPROP 1 LAST OFFPAGE TRUE
J 0
(-3675 1925);
DISPLAY 0.936170 (-3675 1925);
PAINT GREEN (-3675 1925);
DISPLAY INVISIBLE (-3675 1925);
FORCEPROP 1 LAST COMMENT_BODY TRUE
J 0
(-3875 1950);
DISPLAY 0.936170 (-3875 1950);
PAINT GREEN (-3875 1950);
DISPLAY INVISIBLE (-3875 1950);
FORCEPROP 2 LAST PATH I149
J 0
(-3950 2125);
DISPLAY 0.787234 (-3950 2125);
PAINT MONO (-3950 2125);
DISPLAY INVISIBLE (-3950 2125);
FORCEADD TAP..6
R 2
(900 4200);
FORCEPROP 3 LASTPIN (850 4200) SIG_NAME M_M_DQS_DN<8>
J 0
(860 4210);
DISPLAY 0.659574 (860 4210);
PAINT MONO (860 4210);
DISPLAY INVISIBLE (860 4210);
FORCEPROP 1 LASTPIN (850 4200) BN 8
J 2
(900 4210);
DISPLAY 0.617021 (900 4210);
PAINT PINK (900 4210);
FORCEPROP 2 LAST CDS_LIB mstr_standard
J 0
(900 4200);
DISPLAY 0.787234 (900 4200);
PAINT MONO (900 4200);
DISPLAY INVISIBLE (900 4200);
FORCEPROP 1 LAST BODY_TYPE PLUMBING
J 2
(900 4150);
DISPLAY 1.234043 (900 4150);
PAINT GREEN (900 4150);
DISPLAY INVISIBLE (900 4150);
FORCEPROP 1 LAST HDL_TAP TRUE
J 2
(575 4075);
DISPLAY 1.234043 (575 4075);
PAINT GREEN (575 4075);
DISPLAY INVISIBLE (575 4075);
FORCEPROP 1 LAST PATH I15
J 2
(900 4200);
DISPLAY 0.936170 (900 4200);
PAINT GREEN (900 4200);
DISPLAY INVISIBLE (900 4200);
FORCEADD OFFPAGE..6
(-3800 2750);
FORCEPROP 2 LAST $XR1 87 
J 0
(-4139 2750);
DISPLAY 0.638298 (-4139 2750);
PAINT MONO (-4139 2750);
FORCEPROP 2 LAST $XR0 62 
J 0
(-4049 2750);
DISPLAY 0.638298 (-4049 2750);
PAINT MONO (-4049 2750);
FORCEPROP 2 LAST CDS_LIB mstr_standard
J 0
(-3800 2750);
DISPLAY 0.787234 (-3800 2750);
PAINT MONO (-3800 2750);
DISPLAY INVISIBLE (-3800 2750);
FORCEPROP 1 LAST OFFPAGE TRUE
J 0
(-3475 2625);
DISPLAY 0.936170 (-3475 2625);
PAINT GREEN (-3475 2625);
DISPLAY INVISIBLE (-3475 2625);
FORCEPROP 1 LAST COMMENT_BODY TRUE
J 0
(-3700 2675);
DISPLAY 0.936170 (-3700 2675);
PAINT GREEN (-3700 2675);
DISPLAY INVISIBLE (-3700 2675);
FORCEPROP 2 LAST PATH I150
J 0
(-3750 2825);
DISPLAY 0.787234 (-3750 2825);
PAINT MONO (-3750 2825);
DISPLAY INVISIBLE (-3750 2825);
FORCEADD TAP..6
(-3650 3450);
FORCEPROP 3 LASTPIN (-3600 3450) SIG_NAME M_M_CLK_DP<2>
J 0
(-3590 3460);
DISPLAY 0.659574 (-3590 3460);
PAINT MONO (-3590 3460);
DISPLAY INVISIBLE (-3590 3460);
FORCEPROP 1 LASTPIN (-3600 3450) BN 2
J 0
(-3650 3460);
DISPLAY 0.617021 (-3650 3460);
PAINT PINK (-3650 3460);
FORCEPROP 2 LAST CDS_LIB mstr_standard
J 0
(-3650 3450);
DISPLAY 0.787234 (-3650 3450);
PAINT MONO (-3650 3450);
DISPLAY INVISIBLE (-3650 3450);
FORCEPROP 1 LAST BODY_TYPE PLUMBING
J 0
(-3650 3400);
DISPLAY 1.234043 (-3650 3400);
PAINT GREEN (-3650 3400);
DISPLAY INVISIBLE (-3650 3400);
FORCEPROP 1 LAST HDL_TAP TRUE
J 0
(-3325 3325);
DISPLAY 1.234043 (-3325 3325);
PAINT GREEN (-3325 3325);
DISPLAY INVISIBLE (-3325 3325);
FORCEPROP 1 LAST PATH I152
J 0
(-3650 3450);
DISPLAY 0.936170 (-3650 3450);
PAINT GREEN (-3650 3450);
DISPLAY INVISIBLE (-3650 3450);
FORCEADD TAP..6
(-3800 3400);
FORCEPROP 3 LASTPIN (-3750 3400) SIG_NAME M_M_CLK_DN<2>
J 0
(-3740 3410);
DISPLAY 0.659574 (-3740 3410);
PAINT MONO (-3740 3410);
DISPLAY INVISIBLE (-3740 3410);
FORCEPROP 1 LASTPIN (-3750 3400) BN 2
J 0
(-3800 3410);
DISPLAY 0.617021 (-3800 3410);
PAINT PINK (-3800 3410);
FORCEPROP 2 LAST CDS_LIB mstr_standard
J 0
(-3800 3400);
DISPLAY 0.787234 (-3800 3400);
PAINT MONO (-3800 3400);
DISPLAY INVISIBLE (-3800 3400);
FORCEPROP 1 LAST BODY_TYPE PLUMBING
J 0
(-3800 3350);
DISPLAY 1.234043 (-3800 3350);
PAINT GREEN (-3800 3350);
DISPLAY INVISIBLE (-3800 3350);
FORCEPROP 1 LAST HDL_TAP TRUE
J 0
(-3475 3275);
DISPLAY 1.234043 (-3475 3275);
PAINT GREEN (-3475 3275);
DISPLAY INVISIBLE (-3475 3275);
FORCEPROP 1 LAST PATH I153
J 0
(-3800 3400);
DISPLAY 0.936170 (-3800 3400);
PAINT GREEN (-3800 3400);
DISPLAY INVISIBLE (-3800 3400);
FORCEADD OFFPAGE..1
(-4400 3600);
FORCEPROP 2 LAST $XR1 87 
J 0
(-4741 3600);
DISPLAY 0.638298 (-4741 3600);
PAINT MONO (-4741 3600);
FORCEPROP 2 LAST $XR0 62 
J 0
(-4651 3600);
DISPLAY 0.638298 (-4651 3600);
PAINT MONO (-4651 3600);
FORCEPROP 2 LAST CDS_LIB mstr_standard
J 0
(-4400 3600);
DISPLAY 0.787234 (-4400 3600);
PAINT MONO (-4400 3600);
DISPLAY INVISIBLE (-4400 3600);
FORCEPROP 1 LAST OFFPAGE TRUE
J 0
(-4075 3475);
DISPLAY 0.936170 (-4075 3475);
PAINT GREEN (-4075 3475);
DISPLAY INVISIBLE (-4075 3475);
FORCEPROP 1 LAST COMMENT_BODY TRUE
J 0
(-4275 3500);
DISPLAY 0.936170 (-4275 3500);
PAINT GREEN (-4275 3500);
DISPLAY INVISIBLE (-4275 3500);
FORCEPROP 2 LAST PATH I155
J 0
(-4350 3675);
DISPLAY 0.787234 (-4350 3675);
PAINT MONO (-4350 3675);
DISPLAY INVISIBLE (-4350 3675);
FORCEADD OFFPAGE..1
(-4400 3650);
FORCEPROP 2 LAST $XR1 87 
J 0
(-4741 3650);
DISPLAY 0.638298 (-4741 3650);
PAINT MONO (-4741 3650);
FORCEPROP 2 LAST $XR0 62 
J 0
(-4651 3650);
DISPLAY 0.638298 (-4651 3650);
PAINT MONO (-4651 3650);
FORCEPROP 2 LAST CDS_LIB mstr_standard
J 0
(-4400 3650);
DISPLAY 0.787234 (-4400 3650);
PAINT MONO (-4400 3650);
DISPLAY INVISIBLE (-4400 3650);
FORCEPROP 1 LAST OFFPAGE TRUE
J 0
(-4075 3525);
DISPLAY 0.936170 (-4075 3525);
PAINT GREEN (-4075 3525);
DISPLAY INVISIBLE (-4075 3525);
FORCEPROP 1 LAST COMMENT_BODY TRUE
J 0
(-4275 3550);
DISPLAY 0.936170 (-4275 3550);
PAINT GREEN (-4275 3550);
DISPLAY INVISIBLE (-4275 3550);
FORCEPROP 2 LAST PATH I156
J 0
(-4350 3725);
DISPLAY 0.787234 (-4350 3725);
PAINT MONO (-4350 3725);
DISPLAY INVISIBLE (-4350 3725);
FORCEADD OFFPAGE..1
(-3800 3275);
FORCEPROP 2 LAST $XR1 87 
J 0
(-4141 3275);
DISPLAY 0.638298 (-4141 3275);
PAINT MONO (-4141 3275);
FORCEPROP 2 LAST $XR0 62 
J 0
(-4051 3275);
DISPLAY 0.638298 (-4051 3275);
PAINT MONO (-4051 3275);
FORCEPROP 2 LAST CDS_LIB mstr_standard
J 0
(-3800 3275);
DISPLAY 0.787234 (-3800 3275);
PAINT MONO (-3800 3275);
DISPLAY INVISIBLE (-3800 3275);
FORCEPROP 1 LAST OFFPAGE TRUE
J 0
(-3475 3150);
DISPLAY 0.936170 (-3475 3150);
PAINT GREEN (-3475 3150);
DISPLAY INVISIBLE (-3475 3150);
FORCEPROP 1 LAST COMMENT_BODY TRUE
J 0
(-3675 3175);
DISPLAY 0.936170 (-3675 3175);
PAINT GREEN (-3675 3175);
DISPLAY INVISIBLE (-3675 3175);
FORCEPROP 2 LAST PATH I157
J 0
(-3750 3350);
DISPLAY 0.787234 (-3750 3350);
PAINT MONO (-3750 3350);
DISPLAY INVISIBLE (-3750 3350);
FORCEADD OFFPAGE..1
(-3800 2900);
FORCEPROP 2 LAST $XR1 87 
J 0
(-4141 2900);
DISPLAY 0.638298 (-4141 2900);
PAINT MONO (-4141 2900);
FORCEPROP 2 LAST $XR0 62 
J 0
(-4051 2900);
DISPLAY 0.638298 (-4051 2900);
PAINT MONO (-4051 2900);
FORCEPROP 2 LAST CDS_LIB mstr_standard
J 0
(-3800 2900);
DISPLAY 0.787234 (-3800 2900);
PAINT MONO (-3800 2900);
DISPLAY INVISIBLE (-3800 2900);
FORCEPROP 1 LAST OFFPAGE TRUE
J 0
(-3475 2775);
DISPLAY 0.936170 (-3475 2775);
PAINT GREEN (-3475 2775);
DISPLAY INVISIBLE (-3475 2775);
FORCEPROP 1 LAST COMMENT_BODY TRUE
J 0
(-3675 2800);
DISPLAY 0.936170 (-3675 2800);
PAINT GREEN (-3675 2800);
DISPLAY INVISIBLE (-3675 2800);
FORCEPROP 2 LAST PATH I158
J 0
(-3750 2975);
DISPLAY 0.787234 (-3750 2975);
PAINT MONO (-3750 2975);
DISPLAY INVISIBLE (-3750 2975);
FORCEADD OFFPAGE..1
(-3800 3050);
FORCEPROP 2 LAST $XR1 87 
J 0
(-4141 3050);
DISPLAY 0.638298 (-4141 3050);
PAINT MONO (-4141 3050);
FORCEPROP 2 LAST $XR0 62 
J 0
(-4051 3050);
DISPLAY 0.638298 (-4051 3050);
PAINT MONO (-4051 3050);
FORCEPROP 2 LAST CDS_LIB mstr_standard
J 0
(-3800 3050);
DISPLAY 0.787234 (-3800 3050);
PAINT MONO (-3800 3050);
DISPLAY INVISIBLE (-3800 3050);
FORCEPROP 1 LAST OFFPAGE TRUE
J 0
(-3475 2925);
DISPLAY 0.936170 (-3475 2925);
PAINT GREEN (-3475 2925);
DISPLAY INVISIBLE (-3475 2925);
FORCEPROP 1 LAST COMMENT_BODY TRUE
J 0
(-3675 2950);
DISPLAY 0.936170 (-3675 2950);
PAINT GREEN (-3675 2950);
DISPLAY INVISIBLE (-3675 2950);
FORCEPROP 2 LAST PATH I159
J 0
(-3750 3125);
DISPLAY 0.787234 (-3750 3125);
PAINT MONO (-3750 3125);
DISPLAY INVISIBLE (-3750 3125);
FORCEADD TAP..6
R 2
(900 4100);
FORCEPROP 3 LASTPIN (850 4100) SIG_NAME M_M_DQS_DN<7>
J 0
(860 4110);
DISPLAY 0.659574 (860 4110);
PAINT MONO (860 4110);
DISPLAY INVISIBLE (860 4110);
FORCEPROP 1 LASTPIN (850 4100) BN 7
J 2
(900 4110);
DISPLAY 0.617021 (900 4110);
PAINT PINK (900 4110);
FORCEPROP 2 LAST CDS_LIB mstr_standard
J 0
(900 4100);
DISPLAY 0.787234 (900 4100);
PAINT MONO (900 4100);
DISPLAY INVISIBLE (900 4100);
FORCEPROP 1 LAST BODY_TYPE PLUMBING
J 2
(900 4050);
DISPLAY 1.234043 (900 4050);
PAINT GREEN (900 4050);
DISPLAY INVISIBLE (900 4050);
FORCEPROP 1 LAST HDL_TAP TRUE
J 2
(575 3975);
DISPLAY 1.234043 (575 3975);
PAINT GREEN (575 3975);
DISPLAY INVISIBLE (575 3975);
FORCEPROP 1 LAST PATH I16
J 2
(900 4100);
DISPLAY 0.936170 (900 4100);
PAINT GREEN (900 4100);
DISPLAY INVISIBLE (900 4100);
FORCEADD TAP..6
(-3200 3250);
FORCEPROP 3 LASTPIN (-3150 3250) SIG_NAME M_M_CS_N<7>
J 0
(-3140 3260);
DISPLAY 0.659574 (-3140 3260);
PAINT MONO (-3140 3260);
DISPLAY INVISIBLE (-3140 3260);
FORCEPROP 1 LASTPIN (-3150 3250) BN 7
J 0
(-3200 3260);
DISPLAY 0.617021 (-3200 3260);
PAINT PINK (-3200 3260);
FORCEPROP 2 LAST CDS_LIB mstr_standard
J 0
(-3200 3250);
DISPLAY 0.787234 (-3200 3250);
PAINT MONO (-3200 3250);
DISPLAY INVISIBLE (-3200 3250);
FORCEPROP 1 LAST BODY_TYPE PLUMBING
J 0
(-3200 3200);
DISPLAY 1.234043 (-3200 3200);
PAINT GREEN (-3200 3200);
DISPLAY INVISIBLE (-3200 3200);
FORCEPROP 1 LAST HDL_TAP TRUE
J 0
(-2875 3125);
DISPLAY 1.234043 (-2875 3125);
PAINT GREEN (-2875 3125);
DISPLAY INVISIBLE (-2875 3125);
FORCEPROP 1 LAST PATH I160
J 0
(-3200 3250);
DISPLAY 0.936170 (-3200 3250);
PAINT GREEN (-3200 3250);
DISPLAY INVISIBLE (-3200 3250);
FORCEADD TAP..6
(-3200 3200);
FORCEPROP 3 LASTPIN (-3150 3200) SIG_NAME M_M_CS_N<6>
J 0
(-3140 3210);
DISPLAY 0.659574 (-3140 3210);
PAINT MONO (-3140 3210);
DISPLAY INVISIBLE (-3140 3210);
FORCEPROP 1 LASTPIN (-3150 3200) BN 6
J 0
(-3200 3210);
DISPLAY 0.617021 (-3200 3210);
PAINT PINK (-3200 3210);
FORCEPROP 2 LAST CDS_LIB mstr_standard
J 0
(-3200 3200);
DISPLAY 0.787234 (-3200 3200);
PAINT MONO (-3200 3200);
DISPLAY INVISIBLE (-3200 3200);
FORCEPROP 1 LAST BODY_TYPE PLUMBING
J 0
(-3200 3150);
DISPLAY 1.234043 (-3200 3150);
PAINT GREEN (-3200 3150);
DISPLAY INVISIBLE (-3200 3150);
FORCEPROP 1 LAST HDL_TAP TRUE
J 0
(-2875 3075);
DISPLAY 1.234043 (-2875 3075);
PAINT GREEN (-2875 3075);
DISPLAY INVISIBLE (-2875 3075);
FORCEPROP 1 LAST PATH I161
J 0
(-3200 3200);
DISPLAY 0.936170 (-3200 3200);
PAINT GREEN (-3200 3200);
DISPLAY INVISIBLE (-3200 3200);
FORCEADD TAP..6
(-3200 3150);
FORCEPROP 3 LASTPIN (-3150 3150) SIG_NAME M_M_CS_N<5>
J 0
(-3140 3160);
DISPLAY 0.659574 (-3140 3160);
PAINT MONO (-3140 3160);
DISPLAY INVISIBLE (-3140 3160);
FORCEPROP 1 LASTPIN (-3150 3150) BN 5
J 0
(-3200 3160);
DISPLAY 0.617021 (-3200 3160);
PAINT PINK (-3200 3160);
FORCEPROP 2 LAST CDS_LIB mstr_standard
J 0
(-3200 3150);
DISPLAY 0.787234 (-3200 3150);
PAINT MONO (-3200 3150);
DISPLAY INVISIBLE (-3200 3150);
FORCEPROP 1 LAST BODY_TYPE PLUMBING
J 0
(-3200 3100);
DISPLAY 1.234043 (-3200 3100);
PAINT GREEN (-3200 3100);
DISPLAY INVISIBLE (-3200 3100);
FORCEPROP 1 LAST HDL_TAP TRUE
J 0
(-2875 3025);
DISPLAY 1.234043 (-2875 3025);
PAINT GREEN (-2875 3025);
DISPLAY INVISIBLE (-2875 3025);
FORCEPROP 1 LAST PATH I162
J 0
(-3200 3150);
DISPLAY 0.936170 (-3200 3150);
PAINT GREEN (-3200 3150);
DISPLAY INVISIBLE (-3200 3150);
FORCEADD TAP..6
(-3200 3100);
FORCEPROP 3 LASTPIN (-3150 3100) SIG_NAME M_M_CS_N<4>
J 0
(-3140 3110);
DISPLAY 0.659574 (-3140 3110);
PAINT MONO (-3140 3110);
DISPLAY INVISIBLE (-3140 3110);
FORCEPROP 1 LASTPIN (-3150 3100) BN 4
J 0
(-3200 3110);
DISPLAY 0.617021 (-3200 3110);
PAINT PINK (-3200 3110);
FORCEPROP 2 LAST CDS_LIB mstr_standard
J 0
(-3200 3100);
DISPLAY 0.787234 (-3200 3100);
PAINT MONO (-3200 3100);
DISPLAY INVISIBLE (-3200 3100);
FORCEPROP 1 LAST BODY_TYPE PLUMBING
J 0
(-3200 3050);
DISPLAY 1.234043 (-3200 3050);
PAINT GREEN (-3200 3050);
DISPLAY INVISIBLE (-3200 3050);
FORCEPROP 1 LAST HDL_TAP TRUE
J 0
(-2875 2975);
DISPLAY 1.234043 (-2875 2975);
PAINT GREEN (-2875 2975);
DISPLAY INVISIBLE (-2875 2975);
FORCEPROP 1 LAST PATH I163
J 0
(-3200 3100);
DISPLAY 0.936170 (-3200 3100);
PAINT GREEN (-3200 3100);
DISPLAY INVISIBLE (-3200 3100);
FORCEADD TAP..6
(-3200 3000);
FORCEPROP 3 LASTPIN (-3150 3000) SIG_NAME M_M_CKE<3>
J 0
(-3140 3010);
DISPLAY 0.659574 (-3140 3010);
PAINT MONO (-3140 3010);
DISPLAY INVISIBLE (-3140 3010);
FORCEPROP 1 LASTPIN (-3150 3000) BN 3
J 0
(-3200 3010);
DISPLAY 0.617021 (-3200 3010);
PAINT PINK (-3200 3010);
FORCEPROP 2 LAST CDS_LIB mstr_standard
J 0
(-3200 3000);
DISPLAY 0.787234 (-3200 3000);
PAINT MONO (-3200 3000);
DISPLAY INVISIBLE (-3200 3000);
FORCEPROP 1 LAST BODY_TYPE PLUMBING
J 0
(-3200 2950);
DISPLAY 1.234043 (-3200 2950);
PAINT GREEN (-3200 2950);
DISPLAY INVISIBLE (-3200 2950);
FORCEPROP 1 LAST HDL_TAP TRUE
J 0
(-2875 2875);
DISPLAY 1.234043 (-2875 2875);
PAINT GREEN (-2875 2875);
DISPLAY INVISIBLE (-2875 2875);
FORCEPROP 1 LAST PATH I164
J 0
(-3200 3000);
DISPLAY 0.936170 (-3200 3000);
PAINT GREEN (-3200 3000);
DISPLAY INVISIBLE (-3200 3000);
FORCEADD TAP..6
(-3200 2950);
FORCEPROP 3 LASTPIN (-3150 2950) SIG_NAME M_M_CKE<2>
J 0
(-3140 2960);
DISPLAY 0.659574 (-3140 2960);
PAINT MONO (-3140 2960);
DISPLAY INVISIBLE (-3140 2960);
FORCEPROP 1 LASTPIN (-3150 2950) BN 2
J 0
(-3200 2960);
DISPLAY 0.617021 (-3200 2960);
PAINT PINK (-3200 2960);
FORCEPROP 2 LAST CDS_LIB mstr_standard
J 0
(-3200 2950);
DISPLAY 0.787234 (-3200 2950);
PAINT MONO (-3200 2950);
DISPLAY INVISIBLE (-3200 2950);
FORCEPROP 1 LAST BODY_TYPE PLUMBING
J 0
(-3200 2900);
DISPLAY 1.234043 (-3200 2900);
PAINT GREEN (-3200 2900);
DISPLAY INVISIBLE (-3200 2900);
FORCEPROP 1 LAST HDL_TAP TRUE
J 0
(-2875 2825);
DISPLAY 1.234043 (-2875 2825);
PAINT GREEN (-2875 2825);
DISPLAY INVISIBLE (-2875 2825);
FORCEPROP 1 LAST PATH I165
J 0
(-3200 2950);
DISPLAY 0.936170 (-3200 2950);
PAINT GREEN (-3200 2950);
DISPLAY INVISIBLE (-3200 2950);
FORCEADD TAP..6
(-3200 2850);
FORCEPROP 3 LASTPIN (-3150 2850) SIG_NAME M_M_ODT<3>
J 0
(-3140 2860);
DISPLAY 0.659574 (-3140 2860);
PAINT MONO (-3140 2860);
DISPLAY INVISIBLE (-3140 2860);
FORCEPROP 1 LASTPIN (-3150 2850) BN 3
J 0
(-3200 2860);
DISPLAY 0.617021 (-3200 2860);
PAINT PINK (-3200 2860);
FORCEPROP 2 LAST CDS_LIB mstr_standard
J 0
(-3200 2850);
DISPLAY 0.787234 (-3200 2850);
PAINT MONO (-3200 2850);
DISPLAY INVISIBLE (-3200 2850);
FORCEPROP 1 LAST BODY_TYPE PLUMBING
J 0
(-3200 2800);
DISPLAY 1.234043 (-3200 2800);
PAINT GREEN (-3200 2800);
DISPLAY INVISIBLE (-3200 2800);
FORCEPROP 1 LAST HDL_TAP TRUE
J 0
(-2875 2725);
DISPLAY 1.234043 (-2875 2725);
PAINT GREEN (-2875 2725);
DISPLAY INVISIBLE (-2875 2725);
FORCEPROP 1 LAST PATH I166
J 0
(-3200 2850);
DISPLAY 0.936170 (-3200 2850);
PAINT GREEN (-3200 2850);
DISPLAY INVISIBLE (-3200 2850);
FORCEADD TAP..6
(-3200 2800);
FORCEPROP 3 LASTPIN (-3150 2800) SIG_NAME M_M_ODT<2>
J 0
(-3140 2810);
DISPLAY 0.659574 (-3140 2810);
PAINT MONO (-3140 2810);
DISPLAY INVISIBLE (-3140 2810);
FORCEPROP 1 LASTPIN (-3150 2800) BN 2
J 0
(-3200 2810);
DISPLAY 0.617021 (-3200 2810);
PAINT PINK (-3200 2810);
FORCEPROP 2 LAST CDS_LIB mstr_standard
J 0
(-3200 2800);
DISPLAY 0.787234 (-3200 2800);
PAINT MONO (-3200 2800);
DISPLAY INVISIBLE (-3200 2800);
FORCEPROP 1 LAST BODY_TYPE PLUMBING
J 0
(-3200 2750);
DISPLAY 1.234043 (-3200 2750);
PAINT GREEN (-3200 2750);
DISPLAY INVISIBLE (-3200 2750);
FORCEPROP 1 LAST HDL_TAP TRUE
J 0
(-2875 2675);
DISPLAY 1.234043 (-2875 2675);
PAINT GREEN (-2875 2675);
DISPLAY INVISIBLE (-2875 2675);
FORCEPROP 1 LAST PATH I167
J 0
(-3200 2800);
DISPLAY 0.936170 (-3200 2800);
PAINT GREEN (-3200 2800);
DISPLAY INVISIBLE (-3200 2800);
FORCEADD SCONN288_H44441003..4
(-300 2000);
FORCEPROP 1 LAST PART_NUMBER H44441-003
J 0
(-750 950);
DISPLAY 0.617021 (-750 950);
PAINT BLUE (-750 950);
FORCEPROP 2 LASTPIN (-800 2550) $PN 77
J 2
(-810 2560);
DISPLAY 0.617021 (-810 2560);
PAINT ORANGE (-810 2560);
FORCEPROP 2 LASTPIN (-800 2500) $PN 221
J 2
(-810 2510);
DISPLAY 0.617021 (-810 2510);
PAINT ORANGE (-810 2510);
FORCEPROP 2 LASTPIN (-800 2850) $PN 142
J 2
(-810 2860);
DISPLAY 0.617021 (-810 2860);
PAINT ORANGE (-810 2860);
FORCEPROP 2 LASTPIN (-800 2800) $PN 143
J 2
(-810 2810);
DISPLAY 0.617021 (-810 2810);
PAINT ORANGE (-810 2810);
FORCEPROP 2 LASTPIN (-800 2750) $PN 288
J 2
(-810 2760);
DISPLAY 0.617021 (-810 2760);
PAINT ORANGE (-810 2760);
FORCEPROP 2 LASTPIN (-800 2700) $PN 286
J 2
(-810 2710);
DISPLAY 0.617021 (-810 2710);
PAINT ORANGE (-810 2710);
FORCEPROP 2 LASTPIN (-800 2650) $PN 287
J 2
(-810 2660);
DISPLAY 0.617021 (-810 2660);
PAINT ORANGE (-810 2660);
FORCEPROP 2 LASTPIN (-800 2400) $PN 59
J 2
(-810 2410);
DISPLAY 0.617021 (-810 2410);
PAINT ORANGE (-810 2410);
FORCEPROP 2 LASTPIN (-800 2350) $PN 61
J 2
(-810 2360);
DISPLAY 0.617021 (-810 2360);
PAINT ORANGE (-810 2360);
FORCEPROP 2 LASTPIN (-800 2300) $PN 64
J 2
(-810 2310);
DISPLAY 0.617021 (-810 2310);
PAINT ORANGE (-810 2310);
FORCEPROP 2 LASTPIN (-800 2250) $PN 67
J 2
(-810 2260);
DISPLAY 0.617021 (-810 2260);
PAINT ORANGE (-810 2260);
FORCEPROP 2 LASTPIN (-800 2200) $PN 70
J 2
(-810 2210);
DISPLAY 0.617021 (-810 2210);
PAINT ORANGE (-810 2210);
FORCEPROP 2 LASTPIN (-800 2150) $PN 73
J 2
(-810 2160);
DISPLAY 0.617021 (-810 2160);
PAINT ORANGE (-810 2160);
FORCEPROP 2 LASTPIN (-800 2100) $PN 76
J 2
(-810 2110);
DISPLAY 0.617021 (-810 2110);
PAINT ORANGE (-810 2110);
FORCEPROP 2 LASTPIN (-800 2050) $PN 80
J 2
(-810 2060);
DISPLAY 0.617021 (-810 2060);
PAINT ORANGE (-810 2060);
FORCEPROP 2 LASTPIN (-800 2000) $PN 83
J 2
(-810 2010);
DISPLAY 0.617021 (-810 2010);
PAINT ORANGE (-810 2010);
FORCEPROP 2 LASTPIN (-800 1950) $PN 85
J 2
(-810 1960);
DISPLAY 0.617021 (-810 1960);
PAINT ORANGE (-810 1960);
FORCEPROP 2 LASTPIN (-800 1900) $PN 88
J 2
(-810 1910);
DISPLAY 0.617021 (-810 1910);
PAINT ORANGE (-810 1910);
FORCEPROP 2 LASTPIN (-800 1850) $PN 90
J 2
(-810 1860);
DISPLAY 0.617021 (-810 1860);
PAINT ORANGE (-810 1860);
FORCEPROP 2 LASTPIN (-800 1800) $PN 92
J 2
(-810 1810);
DISPLAY 0.617021 (-810 1810);
PAINT ORANGE (-810 1810);
FORCEPROP 2 LASTPIN (-800 1750) $PN 204
J 2
(-810 1760);
DISPLAY 0.617021 (-810 1760);
PAINT ORANGE (-810 1760);
FORCEPROP 2 LASTPIN (-800 1700) $PN 206
J 2
(-810 1710);
DISPLAY 0.617021 (-810 1710);
PAINT ORANGE (-810 1710);
FORCEPROP 2 LASTPIN (-800 1650) $PN 209
J 2
(-810 1660);
DISPLAY 0.617021 (-810 1660);
PAINT ORANGE (-810 1660);
FORCEPROP 2 LASTPIN (-800 1600) $PN 212
J 2
(-810 1610);
DISPLAY 0.617021 (-810 1610);
PAINT ORANGE (-810 1610);
FORCEPROP 2 LASTPIN (-800 1550) $PN 215
J 2
(-810 1560);
DISPLAY 0.617021 (-810 1560);
PAINT ORANGE (-810 1560);
FORCEPROP 2 LASTPIN (-800 1500) $PN 217
J 2
(-810 1510);
DISPLAY 0.617021 (-810 1510);
PAINT ORANGE (-810 1510);
FORCEPROP 2 LASTPIN (-800 1450) $PN 220
J 2
(-810 1460);
DISPLAY 0.617021 (-810 1460);
PAINT ORANGE (-810 1460);
FORCEPROP 2 LASTPIN (-800 1400) $PN 223
J 2
(-810 1410);
DISPLAY 0.617021 (-810 1410);
PAINT ORANGE (-810 1410);
FORCEPROP 2 LASTPIN (-800 1350) $PN 226
J 2
(-810 1360);
DISPLAY 0.617021 (-810 1360);
PAINT ORANGE (-810 1360);
FORCEPROP 2 LASTPIN (-800 1300) $PN 229
J 2
(-810 1310);
DISPLAY 0.617021 (-810 1310);
PAINT ORANGE (-810 1310);
FORCEPROP 2 LASTPIN (-800 1250) $PN 231
J 2
(-810 1260);
DISPLAY 0.617021 (-810 1260);
PAINT ORANGE (-810 1260);
FORCEPROP 2 LASTPIN (-800 1200) $PN 233
J 2
(-810 1210);
DISPLAY 0.617021 (-810 1210);
PAINT ORANGE (-810 1210);
FORCEPROP 2 LASTPIN (-800 1150) $PN 236
J 2
(-810 1160);
DISPLAY 0.617021 (-810 1160);
PAINT ORANGE (-810 1160);
FORCEPROP 2 LASTPIN (200 2850) $PN 1
J 0
(210 2860);
DISPLAY 0.617021 (210 2860);
PAINT ORANGE (210 2860);
FORCEPROP 2 LASTPIN (200 2800) $PN 145
J 0
(210 2810);
DISPLAY 0.617021 (210 2810);
PAINT ORANGE (210 2810);
FORCEPROP 0 LAST BOM_SS NOPOP
J 0
(-436 3042);
DISPLAY 1.021277 (-436 3042);
PAINT BROWN (-436 3042);
DISPLAY BOTH (-436 3042);
FORCEPROP 1 LAST LOCATION J9L1
J 0
(-750 3100);
DISPLAY 0.617021 (-750 3100);
PAINT AQUA (-750 3100);
FORCEPROP 1 LAST MATERIAL SCONN
J 0
(-750 3050);
DISPLAY 0.617021 (-750 3050);
PAINT SKYBLUE (-750 3050);
FORCEPROP 1 LAST PACK_TYPE PIP
J 0
(-750 3150);
PAINT SKYBLUE (-750 3150);
DISPLAY INVISIBLE (-750 3150);
FORCEPROP 2 LAST SEC_TYPE PIP
J 0
(-750 3150);
DISPLAY 1.021277 (-750 3150);
PAINT ORANGE (-750 3150);
DISPLAY INVISIBLE (-750 3150);
FORCEPROP 2 LAST CDS_LIB mstr_sconn
J 0
(-300 2000);
PAINT ORANGE (-300 2000);
DISPLAY INVISIBLE (-300 2000);
FORCEPROP 2 LAST BOM_COST MEM
J 0
(-300 2000);
PAINT ORANGE (-300 2000);
DISPLAY INVISIBLE (-300 2000);
FORCEPROP 2 LAST SEC 4
J 0
(-750 3150);
DISPLAY 0.680851 (-750 3150);
PAINT MONO (-750 3150);
DISPLAY INVISIBLE (-750 3150);
FORCEPROP 2 LAST CDS_LOCATION J9L1
J 0
(-750 3100);
DISPLAY 0.617021 (-750 3100);
PAINT AQUA (-750 3100);
DISPLAY INVISIBLE (-750 3100);
FORCEPROP 1 LAST PATH I168
J 0
(-300 3050);
PAINT GREEN (-300 3050);
DISPLAY INVISIBLE (-300 3050);
FORCEPROP 2 LAST ROOM DDR4_CH_M
J 0
(-300 2000);
PAINT ORANGE (-300 2000);
DISPLAY INVISIBLE (-300 2000);
FORCEADD GND..1
R 2
(2500 1100);
FORCEPROP 3 LASTPIN (2500 1150) SIG_NAME GND\g
J 0
(2510 1160);
DISPLAY 0.659574 (2510 1160);
PAINT MONO (2510 1160);
DISPLAY INVISIBLE (2510 1160);
FORCEPROP 1 LAST VOLTAGE 0
J 0
(2500 1100);
PAINT SKYBLUE (2500 1100);
DISPLAY INVISIBLE (2500 1100);
FORCEPROP 2 LAST CDS_LIB mstr_symbols
J 0
(2500 1100);
DISPLAY 0.787234 (2500 1100);
PAINT MONO (2500 1100);
DISPLAY INVISIBLE (2500 1100);
FORCEPROP 1 LAST SIZE 1B
J 2
(2425 1050);
DISPLAY 1.170213 (2425 1050);
PAINT GREEN (2425 1050);
DISPLAY INVISIBLE (2425 1050);
FORCEPROP 2 LAST BOM_COST MEM
J 0
(2500 1105);
PAINT ORANGE (2500 1105);
DISPLAY INVISIBLE (2500 1105);
FORCEPROP 1 LAST BODY_TYPE PLUMBING
J 2
(2545 1057);
DISPLAY 0.340426 (2545 1057);
PAINT GREEN (2545 1057);
DISPLAY INVISIBLE (2545 1057);
FORCEPROP 1 LAST PATH I169
J 2
(2425 1100);
DISPLAY 1.404255 (2425 1100);
PAINT GREEN (2425 1100);
DISPLAY INVISIBLE (2425 1100);
FORCEPROP 2 LAST ROOM DDR4_CH_D
J 0
(2500 1105);
PAINT ORANGE (2500 1105);
DISPLAY INVISIBLE (2500 1105);
FORCEPROP 1 LAST HDL_POWER GND
J 2
(2500 1250);
DISPLAY 0.553191 (2500 1250);
PAINT GREEN (2500 1250);
DISPLAY INVISIBLE (2500 1250);
FORCEADD TAP..6
R 2
(900 4000);
FORCEPROP 3 LASTPIN (850 4000) SIG_NAME M_M_DQS_DN<6>
J 0
(860 4010);
DISPLAY 0.659574 (860 4010);
PAINT MONO (860 4010);
DISPLAY INVISIBLE (860 4010);
FORCEPROP 1 LASTPIN (850 4000) BN 6
J 2
(900 4010);
DISPLAY 0.617021 (900 4010);
PAINT PINK (900 4010);
FORCEPROP 2 LAST CDS_LIB mstr_standard
J 0
(900 4000);
DISPLAY 0.787234 (900 4000);
PAINT MONO (900 4000);
DISPLAY INVISIBLE (900 4000);
FORCEPROP 1 LAST BODY_TYPE PLUMBING
J 2
(900 3950);
DISPLAY 1.234043 (900 3950);
PAINT GREEN (900 3950);
DISPLAY INVISIBLE (900 3950);
FORCEPROP 1 LAST HDL_TAP TRUE
J 2
(575 3875);
DISPLAY 1.234043 (575 3875);
PAINT GREEN (575 3875);
DISPLAY INVISIBLE (575 3875);
FORCEPROP 1 LAST PATH I17
J 2
(900 4000);
DISPLAY 0.936170 (900 4000);
PAINT GREEN (900 4000);
DISPLAY INVISIBLE (900 4000);
FORCEADD OFFPAGE..1
(-3800 1700);
FORCEPROP 2 LAST $XR5 87 
J 0
(-4501 1700);
DISPLAY 0.638298 (-4501 1700);
PAINT MONO (-4501 1700);
FORCEPROP 2 LAST $XR4 86 
J 0
(-4411 1700);
DISPLAY 0.638298 (-4411 1700);
PAINT MONO (-4411 1700);
FORCEPROP 2 LAST $XR3 85 
J 0
(-4321 1700);
DISPLAY 0.638298 (-4321 1700);
PAINT MONO (-4321 1700);
FORCEPROP 2 LAST $XR2 84 
J 0
(-4231 1700);
DISPLAY 0.638298 (-4231 1700);
PAINT MONO (-4231 1700);
FORCEPROP 2 LAST $XR1 83 
J 0
(-4141 1700);
DISPLAY 0.638298 (-4141 1700);
PAINT MONO (-4141 1700);
FORCEPROP 2 LAST $XR0 99 
J 0
(-4051 1700);
DISPLAY 0.638298 (-4051 1700);
PAINT MONO (-4051 1700);
FORCEPROP 2 LAST CDS_LIB mstr_standard
J 0
(-3800 1700);
DISPLAY 0.787234 (-3800 1700);
PAINT MONO (-3800 1700);
DISPLAY INVISIBLE (-3800 1700);
FORCEPROP 1 LAST OFFPAGE TRUE
J 0
(-3475 1575);
DISPLAY 0.936170 (-3475 1575);
PAINT GREEN (-3475 1575);
DISPLAY INVISIBLE (-3475 1575);
FORCEPROP 1 LAST COMMENT_BODY TRUE
J 0
(-3675 1600);
DISPLAY 0.936170 (-3675 1600);
PAINT GREEN (-3675 1600);
DISPLAY INVISIBLE (-3675 1600);
FORCEPROP 2 LAST PATH I170
J 0
(-4075 1750);
DISPLAY 0.787234 (-4075 1750);
PAINT ORANGE (-4075 1750);
DISPLAY INVISIBLE (-4075 1750);
FORCEADD OFFPAGE..1
(-4800 1600);
FORCEPROP 2 LAST $XR1 87 
J 0
(-5172 1600);
DISPLAY 0.638298 (-5172 1600);
PAINT MONO (-5172 1600);
FORCEPROP 2 LAST $XR0 100 
J 0
(-5082 1600);
DISPLAY 0.638298 (-5082 1600);
PAINT MONO (-5082 1600);
FORCEPROP 2 LAST CDS_LIB mstr_standard
J 0
(-4800 1600);
DISPLAY 0.787234 (-4800 1600);
PAINT MONO (-4800 1600);
DISPLAY INVISIBLE (-4800 1600);
FORCEPROP 1 LAST OFFPAGE TRUE
J 0
(-4475 1475);
DISPLAY 0.936170 (-4475 1475);
PAINT GREEN (-4475 1475);
DISPLAY INVISIBLE (-4475 1475);
FORCEPROP 1 LAST COMMENT_BODY TRUE
J 0
(-4675 1500);
DISPLAY 0.936170 (-4675 1500);
PAINT GREEN (-4675 1500);
DISPLAY INVISIBLE (-4675 1500);
FORCEPROP 2 LAST PATH I171
J 0
(-5050 1650);
DISPLAY 0.787234 (-5050 1650);
PAINT ORANGE (-5050 1650);
DISPLAY INVISIBLE (-5050 1650);
FORCEADD OFFPAGE..6
(-3800 1750);
FORCEPROP 2 LASTPIN (-3750 1750) SIG_NAME SMB_DDR_KLM_VPP_SDA
J 0
(-3710 1760);
DISPLAY 0.617021 (-3710 1760);
PAINT ORANGE (-3710 1760);
FORCEPROP 2 LAST $XR5 99 
J 0
(-4499 1750);
DISPLAY 0.638298 (-4499 1750);
PAINT MONO (-4499 1750);
FORCEPROP 2 LAST $XR4 87 
J 0
(-4409 1750);
DISPLAY 0.638298 (-4409 1750);
PAINT MONO (-4409 1750);
FORCEPROP 2 LAST $XR3 86 
J 0
(-4319 1750);
DISPLAY 0.638298 (-4319 1750);
PAINT MONO (-4319 1750);
FORCEPROP 2 LAST $XR2 85 
J 0
(-4229 1750);
DISPLAY 0.638298 (-4229 1750);
PAINT MONO (-4229 1750);
FORCEPROP 2 LAST $XR1 84 
J 0
(-4139 1750);
DISPLAY 0.638298 (-4139 1750);
PAINT MONO (-4139 1750);
FORCEPROP 2 LAST $XR0 83 
J 0
(-4049 1750);
DISPLAY 0.638298 (-4049 1750);
PAINT MONO (-4049 1750);
FORCEPROP 2 LAST CDS_LIB mstr_standard
J 0
(-3800 1750);
DISPLAY 0.787234 (-3800 1750);
PAINT MONO (-3800 1750);
DISPLAY INVISIBLE (-3800 1750);
FORCEPROP 1 LAST OFFPAGE TRUE
J 0
(-3475 1625);
DISPLAY 0.936170 (-3475 1625);
PAINT GREEN (-3475 1625);
DISPLAY INVISIBLE (-3475 1625);
FORCEPROP 1 LAST COMMENT_BODY TRUE
J 0
(-3700 1675);
DISPLAY 0.936170 (-3700 1675);
PAINT GREEN (-3700 1675);
DISPLAY INVISIBLE (-3700 1675);
FORCEPROP 2 LAST PATH I172
J 0
(-4100 1800);
DISPLAY 0.787234 (-4100 1800);
PAINT ORANGE (-4100 1800);
DISPLAY INVISIBLE (-4100 1800);
FORCEADD OFFPAGE..5
(-4175 2450);
FORCEPROP 2 LAST $XR23 94 
J 0
(-4789 2486);
DISPLAY 0.638298 (-4789 2486);
PAINT MONO (-4789 2486);
FORCEPROP 2 LAST $XR22 87 
J 0
(-4699 2486);
DISPLAY 0.638298 (-4699 2486);
PAINT MONO (-4699 2486);
FORCEPROP 2 LAST $XR21 86 
J 0
(-4609 2486);
DISPLAY 0.638298 (-4609 2486);
PAINT MONO (-4609 2486);
FORCEPROP 2 LAST $XR20 85 
J 0
(-4519 2486);
DISPLAY 0.638298 (-4519 2486);
PAINT MONO (-4519 2486);
FORCEPROP 2 LAST $XR19 84 
J 0
(-4429 2486);
DISPLAY 0.638298 (-4429 2486);
PAINT MONO (-4429 2486);
FORCEPROP 2 LAST $XR18 83 
J 0
(-5149 2414);
DISPLAY 0.638298 (-5149 2414);
PAINT MONO (-5149 2414);
FORCEPROP 2 LAST $XR17 82 
J 0
(-5059 2414);
DISPLAY 0.638298 (-5059 2414);
PAINT MONO (-5059 2414);
FORCEPROP 2 LAST $XR16 81 
J 0
(-4969 2414);
DISPLAY 0.638298 (-4969 2414);
PAINT MONO (-4969 2414);
FORCEPROP 2 LAST $XR15 80 
J 0
(-4879 2414);
DISPLAY 0.638298 (-4879 2414);
PAINT MONO (-4879 2414);
FORCEPROP 2 LAST $XR14 79 
J 0
(-4789 2414);
DISPLAY 0.638298 (-4789 2414);
PAINT MONO (-4789 2414);
FORCEPROP 2 LAST $XR13 78 
J 0
(-4699 2414);
DISPLAY 0.638298 (-4699 2414);
PAINT MONO (-4699 2414);
FORCEPROP 2 LAST $XR12 77 
J 0
(-4609 2414);
DISPLAY 0.638298 (-4609 2414);
PAINT MONO (-4609 2414);
FORCEPROP 2 LAST $XR11 54 
J 0
(-4519 2414);
DISPLAY 0.638298 (-4519 2414);
PAINT MONO (-4519 2414);
FORCEPROP 2 LAST $XR10 53 
J 0
(-4429 2414);
DISPLAY 0.638298 (-4429 2414);
PAINT MONO (-4429 2414);
FORCEPROP 2 LAST $XR9 52 
J 0
(-5239 2450);
DISPLAY 0.638298 (-5239 2450);
PAINT MONO (-5239 2450);
FORCEPROP 2 LAST $XR8 51 
J 0
(-5149 2450);
DISPLAY 0.638298 (-5149 2450);
PAINT MONO (-5149 2450);
FORCEPROP 2 LAST $XR7 50 
J 0
(-5059 2450);
DISPLAY 0.638298 (-5059 2450);
PAINT MONO (-5059 2450);
FORCEPROP 2 LAST $XR6 49 
J 0
(-4969 2450);
DISPLAY 0.638298 (-4969 2450);
PAINT MONO (-4969 2450);
FORCEPROP 2 LAST $XR5 48 
J 0
(-4879 2450);
DISPLAY 0.638298 (-4879 2450);
PAINT MONO (-4879 2450);
FORCEPROP 2 LAST $XR4 47 
J 0
(-4789 2450);
DISPLAY 0.638298 (-4789 2450);
PAINT MONO (-4789 2450);
FORCEPROP 2 LAST $XR3 46 
J 0
(-4699 2450);
DISPLAY 0.638298 (-4699 2450);
PAINT MONO (-4699 2450);
FORCEPROP 2 LAST $XR2 45 
J 0
(-4609 2450);
DISPLAY 0.638298 (-4609 2450);
PAINT MONO (-4609 2450);
FORCEPROP 2 LAST $XR1 44 
J 0
(-4519 2450);
DISPLAY 0.638298 (-4519 2450);
PAINT MONO (-4519 2450);
FORCEPROP 2 LAST $XR0 43 
J 0
(-4429 2450);
DISPLAY 0.638298 (-4429 2450);
PAINT MONO (-4429 2450);
FORCEPROP 2 LAST CDS_LIB mstr_standard
J 0
(-4175 2450);
DISPLAY 0.787234 (-4175 2450);
PAINT MONO (-4175 2450);
DISPLAY INVISIBLE (-4175 2450);
FORCEPROP 1 LAST OFFPAGE TRUE
J 0
(-3850 2325);
DISPLAY 1.404255 (-3850 2325);
PAINT GREEN (-3850 2325);
DISPLAY INVISIBLE (-3850 2325);
FORCEPROP 1 LAST COMMENT_BODY TRUE
J 0
(-4075 2375);
DISPLAY 1.404255 (-4075 2375);
PAINT GREEN (-4075 2375);
DISPLAY INVISIBLE (-4075 2375);
FORCEPROP 2 LAST PATH I173
J 0
(-4125 2525);
DISPLAY 0.787234 (-4125 2525);
PAINT ORANGE (-4125 2525);
DISPLAY INVISIBLE (-4125 2525);
FORCEADD GND..1
R 2
(-5200 1725);
FORCEPROP 3 LASTPIN (-5200 1775) SIG_NAME GND\g
J 0
(-5190 1785);
DISPLAY 0.659574 (-5190 1785);
PAINT MONO (-5190 1785);
DISPLAY INVISIBLE (-5190 1785);
FORCEPROP 1 LAST VOLTAGE 0
J 0
(-5200 1725);
PAINT SKYBLUE (-5200 1725);
DISPLAY INVISIBLE (-5200 1725);
FORCEPROP 2 LAST BOM_COST MEM
J 0
(-5200 1730);
PAINT ORANGE (-5200 1730);
DISPLAY INVISIBLE (-5200 1730);
FORCEPROP 2 LAST CDS_LIB mstr_symbols
J 0
(-5200 1725);
DISPLAY 0.787234 (-5200 1725);
PAINT MONO (-5200 1725);
DISPLAY INVISIBLE (-5200 1725);
FORCEPROP 1 LAST SIZE 1B
J 2
(-5275 1675);
DISPLAY 1.170213 (-5275 1675);
PAINT GREEN (-5275 1675);
DISPLAY INVISIBLE (-5275 1675);
FORCEPROP 1 LAST BODY_TYPE PLUMBING
J 2
(-5155 1682);
DISPLAY 0.340426 (-5155 1682);
PAINT GREEN (-5155 1682);
DISPLAY INVISIBLE (-5155 1682);
FORCEPROP 1 LAST PATH I175
J 2
(-5275 1725);
DISPLAY 1.404255 (-5275 1725);
PAINT GREEN (-5275 1725);
DISPLAY INVISIBLE (-5275 1725);
FORCEPROP 2 LAST ROOM DDR4_CH_D
J 0
(-5200 1730);
PAINT ORANGE (-5200 1730);
DISPLAY INVISIBLE (-5200 1730);
FORCEPROP 1 LAST HDL_POWER GND
J 2
(-5200 1875);
DISPLAY 0.553191 (-5200 1875);
PAINT GREEN (-5200 1875);
DISPLAY INVISIBLE (-5200 1875);
FORCEADD GND..1
(-4650 1150);
FORCEPROP 3 LASTPIN (-4650 1200) SIG_NAME GND\g
J 0
(-4640 1210);
DISPLAY 0.659574 (-4640 1210);
PAINT MONO (-4640 1210);
DISPLAY INVISIBLE (-4640 1210);
FORCEPROP 1 LAST VOLTAGE 0
J 0
(-4650 1150);
PAINT SKYBLUE (-4650 1150);
DISPLAY INVISIBLE (-4650 1150);
FORCEPROP 1 LAST SIZE 1B
J 0
(-4575 1100);
DISPLAY 1.787234 (-4575 1100);
PAINT GREEN (-4575 1100);
DISPLAY INVISIBLE (-4575 1100);
FORCEPROP 2 LAST CDS_LIB mstr_symbols
J 0
(-4650 1150);
PAINT ORANGE (-4650 1150);
DISPLAY INVISIBLE (-4650 1150);
FORCEPROP 2 LAST BOM_COST MEM
J 0
(-4650 1155);
PAINT ORANGE (-4650 1155);
DISPLAY INVISIBLE (-4650 1155);
FORCEPROP 1 LAST BODY_TYPE PLUMBING
J 0
(-4695 1107);
DISPLAY 0.340426 (-4695 1107);
PAINT GREEN (-4695 1107);
DISPLAY INVISIBLE (-4695 1107);
FORCEPROP 1 LAST PATH I176
J 0
(-4575 1150);
DISPLAY 1.404255 (-4575 1150);
PAINT GREEN (-4575 1150);
DISPLAY INVISIBLE (-4575 1150);
FORCEPROP 2 LAST ROOM DDR4_CH_D
J 0
(-4650 1155);
PAINT ORANGE (-4650 1155);
DISPLAY INVISIBLE (-4650 1155);
FORCEPROP 1 LAST HDL_POWER GND
J 0
(-4650 1300);
DISPLAY 1.404255 (-4650 1300);
PAINT GREEN (-4650 1300);
DISPLAY INVISIBLE (-4650 1300);
FORCEADD CAP_A..1
R 2
(-4650 1400);
FORCEPROP 1 LAST LOCATION C9L1
J 2
(-4700 1500);
DISPLAY 0.617021 (-4700 1500);
PAINT AQUA (-4700 1500);
FORCEPROP 1 LAST PART_NUMBER A36096-045
J 2
(-4700 1250);
DISPLAY 0.617021 (-4700 1250);
PAINT BLUE (-4700 1250);
FORCEPROP 1 LAST VALUE 0.01UF
J 2
(-4700 1450);
DISPLAY 0.617021 (-4700 1450);
PAINT SKYBLUE (-4700 1450);
FORCEPROP 1 LAST TOLERANCE 10%
J 2
(-4700 1350);
DISPLAY 0.617021 (-4700 1350);
PAINT SKYBLUE (-4700 1350);
FORCEPROP 1 LAST PACK_TYPE 0402V
J 2
(-4700 1200);
DISPLAY 0.617021 (-4700 1200);
PAINT SKYBLUE (-4700 1200);
FORCEPROP 1 LAST VOLTAGE 25V
J 2
(-4700 1400);
DISPLAY 0.617021 (-4700 1400);
PAINT SKYBLUE (-4700 1400);
FORCEPROP 1 LAST MATERIAL X7R
J 2
(-4700 1300);
DISPLAY 0.617021 (-4700 1300);
PAINT SKYBLUE (-4700 1300);
FORCEPROP 1 LASTPIN (-4650 1500) $PN 1
J 2
(-4660 1480);
DISPLAY 0.617021 (-4660 1480);
PAINT ORANGE (-4660 1480);
FORCEPROP 1 LASTPIN (-4650 1300) $PN 2
J 2
(-4660 1280);
DISPLAY 0.617021 (-4660 1280);
PAINT ORANGE (-4660 1280);
FORCEPROP 2 LAST CDS_LOCATION C9L1
J 2
(-4700 1500);
DISPLAY 0.617021 (-4700 1500);
PAINT AQUA (-4700 1500);
DISPLAY INVISIBLE (-4700 1500);
FORCEPROP 2 LAST BOM_COST MEM
J 0
(-4650 1400);
PAINT ORANGE (-4650 1400);
DISPLAY INVISIBLE (-4650 1400);
FORCEPROP 2 LAST CDS_LIB dev_discrete
J 0
(-4650 1400);
PAINT ORANGE (-4650 1400);
DISPLAY INVISIBLE (-4650 1400);
FORCEPROP 2 LAST CDS_SEC 1
J 0
(-4700 1550);
PAINT ORANGE (-4700 1550);
DISPLAY INVISIBLE (-4700 1550);
FORCEPROP 2 LAST SEC_TYPE 0402V
J 0
(-4700 1600);
DISPLAY 1.021277 (-4700 1600);
PAINT ORANGE (-4700 1600);
DISPLAY INVISIBLE (-4700 1600);
FORCEPROP 2 LAST SEC 1
J 0
(-4700 1600);
DISPLAY 0.680851 (-4700 1600);
PAINT MONO (-4700 1600);
DISPLAY INVISIBLE (-4700 1600);
FORCEPROP 1 LAST PATH I177
J 2
(-4700 1550);
DISPLAY 0.978723 (-4700 1550);
PAINT WHITE (-4700 1550);
DISPLAY INVISIBLE (-4700 1550);
FORCEPROP 2 LAST ROOM DDR4_CH_M1
J 0
(-4650 1400);
PAINT ORANGE (-4650 1400);
DISPLAY INVISIBLE (-4650 1400);
FORCEADD PVPP_KLM..1
(-5200 2100);
FORCEPROP 3 LASTPIN (-5200 2050) SIG_NAME PVPP_KLM\g
J 0
(-5190 2060);
DISPLAY 0.659574 (-5190 2060);
PAINT MONO (-5190 2060);
DISPLAY INVISIBLE (-5190 2060);
FORCEPROP 1 LAST VOLTAGE 2.5V
J 0
(-5245 2057);
DISPLAY 0.340426 (-5245 2057);
PAINT SKYBLUE (-5245 2057);
DISPLAY INVISIBLE (-5245 2057);
FORCEPROP 0 LAST BOM_COST MEM
J 0
(-5200 2200);
PAINT ORANGE (-5200 2200);
DISPLAY INVISIBLE (-5200 2200);
FORCEPROP 2 LAST CDS_LIB mstr_symbols
J 0
(-5200 2100);
PAINT ORANGE (-5200 2100);
DISPLAY INVISIBLE (-5200 2100);
FORCEPROP 1 LAST BODY_TYPE PLUMBING
J 0
(-5245 2057);
DISPLAY 0.340426 (-5245 2057);
PAINT GREEN (-5245 2057);
DISPLAY INVISIBLE (-5245 2057);
FORCEPROP 1 LAST PATH I178
J 0
(-5150 2125);
DISPLAY 0.872340 (-5150 2125);
PAINT AQUA (-5150 2125);
DISPLAY INVISIBLE (-5150 2125);
FORCEPROP 2 LAST ROOM DDR4_CH_D
J 0
(-5200 2200);
PAINT ORANGE (-5200 2200);
DISPLAY INVISIBLE (-5200 2200);
FORCEPROP 1 LAST HDL_POWER PVPP_KLM
J 1
(-5200 2150);
DISPLAY 0.872340 (-5200 2150);
PAINT GREEN (-5200 2150);
DISPLAY INVISIBLE (-5200 2150);
FORCEADD PVPP_KLM..1
(-1000 3025);
FORCEPROP 3 LASTPIN (-1000 2975) SIG_NAME PVPP_KLM\g
J 0
(-990 2985);
DISPLAY 0.659574 (-990 2985);
PAINT MONO (-990 2985);
DISPLAY INVISIBLE (-990 2985);
FORCEPROP 1 LAST VOLTAGE 2.5V
J 0
(-1045 2982);
DISPLAY 0.340426 (-1045 2982);
PAINT SKYBLUE (-1045 2982);
DISPLAY INVISIBLE (-1045 2982);
FORCEPROP 0 LAST BOM_COST MEM
J 0
(-1000 3125);
PAINT ORANGE (-1000 3125);
DISPLAY INVISIBLE (-1000 3125);
FORCEPROP 2 LAST CDS_LIB mstr_symbols
J 0
(-1000 3025);
PAINT ORANGE (-1000 3025);
DISPLAY INVISIBLE (-1000 3025);
FORCEPROP 1 LAST BODY_TYPE PLUMBING
J 0
(-1045 2982);
DISPLAY 0.340426 (-1045 2982);
PAINT GREEN (-1045 2982);
DISPLAY INVISIBLE (-1045 2982);
FORCEPROP 1 LAST PATH I179
J 0
(-950 3050);
DISPLAY 0.872340 (-950 3050);
PAINT AQUA (-950 3050);
DISPLAY INVISIBLE (-950 3050);
FORCEPROP 2 LAST ROOM DDR4_CH_D
J 0
(-1000 3125);
PAINT ORANGE (-1000 3125);
DISPLAY INVISIBLE (-1000 3125);
FORCEPROP 1 LAST HDL_POWER PVPP_KLM
J 1
(-1000 3075);
DISPLAY 0.872340 (-1000 3075);
PAINT GREEN (-1000 3075);
DISPLAY INVISIBLE (-1000 3075);
FORCEADD TAP..6
R 2
(900 3900);
FORCEPROP 3 LASTPIN (850 3900) SIG_NAME M_M_DQS_DN<5>
J 0
(860 3910);
DISPLAY 0.659574 (860 3910);
PAINT MONO (860 3910);
DISPLAY INVISIBLE (860 3910);
FORCEPROP 1 LASTPIN (850 3900) BN 5
J 2
(900 3910);
DISPLAY 0.617021 (900 3910);
PAINT PINK (900 3910);
FORCEPROP 2 LAST CDS_LIB mstr_standard
J 0
(900 3900);
DISPLAY 0.787234 (900 3900);
PAINT MONO (900 3900);
DISPLAY INVISIBLE (900 3900);
FORCEPROP 1 LAST BODY_TYPE PLUMBING
J 2
(900 3850);
DISPLAY 1.234043 (900 3850);
PAINT GREEN (900 3850);
DISPLAY INVISIBLE (900 3850);
FORCEPROP 1 LAST HDL_TAP TRUE
J 2
(575 3775);
DISPLAY 1.234043 (575 3775);
PAINT GREEN (575 3775);
DISPLAY INVISIBLE (575 3775);
FORCEPROP 1 LAST PATH I18
J 2
(900 3900);
DISPLAY 0.936170 (900 3900);
PAINT GREEN (900 3900);
DISPLAY INVISIBLE (900 3900);
FORCEADD OFFPAGE..1
(-3850 1300);
FORCEPROP 2 LAST $XR5 87 
J 0
(-4551 1300);
DISPLAY 0.638298 (-4551 1300);
PAINT MONO (-4551 1300);
FORCEPROP 2 LAST $XR4 86 
J 0
(-4461 1300);
DISPLAY 0.638298 (-4461 1300);
PAINT MONO (-4461 1300);
FORCEPROP 2 LAST $XR3 85 
J 0
(-4371 1300);
DISPLAY 0.638298 (-4371 1300);
PAINT MONO (-4371 1300);
FORCEPROP 2 LAST $XR2 84 
J 0
(-4281 1300);
DISPLAY 0.638298 (-4281 1300);
PAINT MONO (-4281 1300);
FORCEPROP 2 LAST $XR1 83 
J 0
(-4191 1300);
DISPLAY 0.638298 (-4191 1300);
PAINT MONO (-4191 1300);
FORCEPROP 2 LAST $XR0 89 
J 0
(-4101 1300);
DISPLAY 0.638298 (-4101 1300);
PAINT MONO (-4101 1300);
FORCEPROP 2 LAST CDS_LIB mstr_standard
J 0
(-3850 1300);
PAINT ORANGE (-3850 1300);
DISPLAY INVISIBLE (-3850 1300);
FORCEPROP 1 LAST OFFPAGE TRUE
J 0
(-3525 1175);
DISPLAY 0.936170 (-3525 1175);
PAINT GREEN (-3525 1175);
DISPLAY INVISIBLE (-3525 1175);
FORCEPROP 1 LAST COMMENT_BODY TRUE
J 0
(-3725 1200);
DISPLAY 0.936170 (-3725 1200);
PAINT GREEN (-3725 1200);
DISPLAY INVISIBLE (-3725 1200);
FORCEPROP 2 LAST PATH I180
J 0
(-3800 1375);
PAINT ORANGE (-3800 1375);
DISPLAY INVISIBLE (-3800 1375);
FORCEADD TAP..6
(-3650 3550);
FORCEPROP 3 LASTPIN (-3600 3550) SIG_NAME M_M_CLK_DP<3>
J 0
(-3590 3560);
DISPLAY 0.659574 (-3590 3560);
PAINT MONO (-3590 3560);
DISPLAY INVISIBLE (-3590 3560);
FORCEPROP 1 LASTPIN (-3600 3550) BN 3
J 0
(-3652 3558);
DISPLAY 0.617021 (-3652 3558);
PAINT PINK (-3652 3558);
FORCEPROP 2 LAST CDS_LIB mstr_standard
J 0
(-3650 3550);
PAINT MONO (-3650 3550);
DISPLAY INVISIBLE (-3650 3550);
FORCEPROP 1 LAST BODY_TYPE PLUMBING
J 0
(-3650 3500);
DISPLAY 1.234043 (-3650 3500);
PAINT GREEN (-3650 3500);
DISPLAY INVISIBLE (-3650 3500);
FORCEPROP 1 LAST HDL_TAP TRUE
J 0
(-3325 3425);
DISPLAY 1.234043 (-3325 3425);
PAINT GREEN (-3325 3425);
DISPLAY INVISIBLE (-3325 3425);
FORCEPROP 1 LAST PATH I184
J 0
(-3652 3550);
DISPLAY 0.872340 (-3652 3550);
PAINT GREEN (-3652 3550);
DISPLAY INVISIBLE (-3652 3550);
FORCEADD TAP..6
(-3800 3500);
FORCEPROP 3 LASTPIN (-3750 3500) SIG_NAME M_M_CLK_DN<3>
J 0
(-3740 3510);
DISPLAY 0.659574 (-3740 3510);
PAINT MONO (-3740 3510);
DISPLAY INVISIBLE (-3740 3510);
FORCEPROP 1 LASTPIN (-3750 3500) BN 3
J 0
(-3802 3508);
DISPLAY 0.617021 (-3802 3508);
PAINT PINK (-3802 3508);
FORCEPROP 2 LAST CDS_LIB mstr_standard
J 0
(-3800 3500);
PAINT MONO (-3800 3500);
DISPLAY INVISIBLE (-3800 3500);
FORCEPROP 1 LAST BODY_TYPE PLUMBING
J 0
(-3800 3450);
DISPLAY 1.234043 (-3800 3450);
PAINT GREEN (-3800 3450);
DISPLAY INVISIBLE (-3800 3450);
FORCEPROP 1 LAST HDL_TAP TRUE
J 0
(-3475 3375);
DISPLAY 1.234043 (-3475 3375);
PAINT GREEN (-3475 3375);
DISPLAY INVISIBLE (-3475 3375);
FORCEPROP 1 LAST PATH I185
J 0
(-3802 3500);
DISPLAY 0.872340 (-3802 3500);
PAINT GREEN (-3802 3500);
DISPLAY INVISIBLE (-3802 3500);
FORCEADD P12V_NVDIMM_KLM..1
(400 3000);
FORCEPROP 3 LASTPIN (400 2950) SIG_NAME P12V_NVDIMM_KLM\g
J 0
(410 2960);
DISPLAY 0.659574 (410 2960);
PAINT MONO (410 2960);
DISPLAY INVISIBLE (410 2960);
FORCEPROP 1 LAST VOLTAGE 12.0
J 0
(355 2957);
DISPLAY 0.340426 (355 2957);
PAINT SKYBLUE (355 2957);
DISPLAY INVISIBLE (355 2957);
FORCEPROP 2 LAST CDS_LIB mstr_symbols
J 0
(400 3000);
PAINT ORANGE (400 3000);
DISPLAY INVISIBLE (400 3000);
FORCEPROP 1 LAST BODY_TYPE PLUMBING
J 0
(355 2957);
DISPLAY 0.340426 (355 2957);
PAINT GREEN (355 2957);
DISPLAY INVISIBLE (355 2957);
FORCEPROP 1 LAST PATH I186
J 0
(450 3025);
DISPLAY 0.872340 (450 3025);
PAINT AQUA (450 3025);
DISPLAY INVISIBLE (450 3025);
FORCEPROP 1 LAST HDL_POWER P12V_NVDIMM_KLM
J 1
(400 3050);
DISPLAY 0.872340 (400 3050);
PAINT GREEN (400 3050);
DISPLAY INVISIBLE (400 3050);
FORCEADD TAP..6
R 2
(900 3800);
FORCEPROP 3 LASTPIN (850 3800) SIG_NAME M_M_DQS_DN<4>
J 0
(860 3810);
DISPLAY 0.659574 (860 3810);
PAINT MONO (860 3810);
DISPLAY INVISIBLE (860 3810);
FORCEPROP 1 LASTPIN (850 3800) BN 4
J 2
(900 3810);
DISPLAY 0.617021 (900 3810);
PAINT PINK (900 3810);
FORCEPROP 2 LAST CDS_LIB mstr_standard
J 0
(900 3800);
DISPLAY 0.787234 (900 3800);
PAINT MONO (900 3800);
DISPLAY INVISIBLE (900 3800);
FORCEPROP 1 LAST BODY_TYPE PLUMBING
J 2
(900 3750);
DISPLAY 1.234043 (900 3750);
PAINT GREEN (900 3750);
DISPLAY INVISIBLE (900 3750);
FORCEPROP 1 LAST HDL_TAP TRUE
J 2
(575 3675);
DISPLAY 1.234043 (575 3675);
PAINT GREEN (575 3675);
DISPLAY INVISIBLE (575 3675);
FORCEPROP 1 LAST PATH I19
J 2
(900 3800);
DISPLAY 0.936170 (900 3800);
PAINT GREEN (900 3800);
DISPLAY INVISIBLE (900 3800);
FORCEADD OFFPAGE..3
(1600 5150);
FORCEPROP 2 LAST $XR1 87 
J 0
(1904 5150);
DISPLAY 0.638298 (1904 5150);
PAINT MONO (1904 5150);
FORCEPROP 2 LAST $XR0 62 
J 0
(1814 5150);
DISPLAY 0.638298 (1814 5150);
PAINT MONO (1814 5150);
FORCEPROP 2 LAST CDS_LIB mstr_standard
J 0
(1600 5150);
DISPLAY 0.787234 (1600 5150);
PAINT MONO (1600 5150);
DISPLAY INVISIBLE (1600 5150);
FORCEPROP 1 LAST OFFPAGE TRUE
J 0
(1925 5025);
DISPLAY 0.936170 (1925 5025);
PAINT GREEN (1925 5025);
DISPLAY INVISIBLE (1925 5025);
FORCEPROP 1 LAST COMMENT_BODY TRUE
J 0
(1550 5050);
DISPLAY 0.936170 (1550 5050);
PAINT GREEN (1550 5050);
DISPLAY INVISIBLE (1550 5050);
FORCEPROP 2 LAST PATH I2
J 0
(1800 5225);
DISPLAY 0.787234 (1800 5225);
PAINT MONO (1800 5225);
DISPLAY INVISIBLE (1800 5225);
FORCEADD TAP..6
R 2
(900 3700);
FORCEPROP 3 LASTPIN (850 3700) SIG_NAME M_M_DQS_DN<3>
J 0
(860 3710);
DISPLAY 0.659574 (860 3710);
PAINT MONO (860 3710);
DISPLAY INVISIBLE (860 3710);
FORCEPROP 1 LASTPIN (850 3700) BN 3
J 2
(900 3710);
DISPLAY 0.617021 (900 3710);
PAINT PINK (900 3710);
FORCEPROP 2 LAST CDS_LIB mstr_standard
J 0
(900 3700);
DISPLAY 0.787234 (900 3700);
PAINT MONO (900 3700);
DISPLAY INVISIBLE (900 3700);
FORCEPROP 1 LAST BODY_TYPE PLUMBING
J 2
(900 3650);
DISPLAY 1.234043 (900 3650);
PAINT GREEN (900 3650);
DISPLAY INVISIBLE (900 3650);
FORCEPROP 1 LAST HDL_TAP TRUE
J 2
(575 3575);
DISPLAY 1.234043 (575 3575);
PAINT GREEN (575 3575);
DISPLAY INVISIBLE (575 3575);
FORCEPROP 1 LAST PATH I20
J 2
(900 3700);
DISPLAY 0.936170 (900 3700);
PAINT GREEN (900 3700);
DISPLAY INVISIBLE (900 3700);
FORCEADD TAP..6
R 2
(900 3500);
FORCEPROP 3 LASTPIN (850 3500) SIG_NAME M_M_DQS_DN<1>
J 0
(860 3510);
DISPLAY 0.659574 (860 3510);
PAINT MONO (860 3510);
DISPLAY INVISIBLE (860 3510);
FORCEPROP 1 LASTPIN (850 3500) BN 1
J 2
(900 3510);
DISPLAY 0.617021 (900 3510);
PAINT PINK (900 3510);
FORCEPROP 2 LAST CDS_LIB mstr_standard
J 0
(900 3500);
DISPLAY 0.787234 (900 3500);
PAINT MONO (900 3500);
DISPLAY INVISIBLE (900 3500);
FORCEPROP 1 LAST BODY_TYPE PLUMBING
J 2
(900 3450);
DISPLAY 1.234043 (900 3450);
PAINT GREEN (900 3450);
DISPLAY INVISIBLE (900 3450);
FORCEPROP 1 LAST HDL_TAP TRUE
J 2
(575 3375);
DISPLAY 1.234043 (575 3375);
PAINT GREEN (575 3375);
DISPLAY INVISIBLE (575 3375);
FORCEPROP 1 LAST PATH I21
J 2
(900 3500);
DISPLAY 0.936170 (900 3500);
PAINT GREEN (900 3500);
DISPLAY INVISIBLE (900 3500);
FORCEADD TAP..6
R 2
(900 3600);
FORCEPROP 3 LASTPIN (850 3600) SIG_NAME M_M_DQS_DN<2>
J 0
(860 3610);
DISPLAY 0.659574 (860 3610);
PAINT MONO (860 3610);
DISPLAY INVISIBLE (860 3610);
FORCEPROP 1 LASTPIN (850 3600) BN 2
J 2
(900 3610);
DISPLAY 0.617021 (900 3610);
PAINT PINK (900 3610);
FORCEPROP 2 LAST CDS_LIB mstr_standard
J 0
(900 3600);
DISPLAY 0.787234 (900 3600);
PAINT MONO (900 3600);
DISPLAY INVISIBLE (900 3600);
FORCEPROP 1 LAST BODY_TYPE PLUMBING
J 2
(900 3550);
DISPLAY 1.234043 (900 3550);
PAINT GREEN (900 3550);
DISPLAY INVISIBLE (900 3550);
FORCEPROP 1 LAST HDL_TAP TRUE
J 2
(575 3475);
DISPLAY 1.234043 (575 3475);
PAINT GREEN (575 3475);
DISPLAY INVISIBLE (575 3475);
FORCEPROP 1 LAST PATH I22
J 2
(900 3600);
DISPLAY 0.936170 (900 3600);
PAINT GREEN (900 3600);
DISPLAY INVISIBLE (900 3600);
FORCEADD TAP..6
R 2
(900 3400);
FORCEPROP 3 LASTPIN (850 3400) SIG_NAME M_M_DQS_DN<0>
J 0
(860 3410);
DISPLAY 0.659574 (860 3410);
PAINT MONO (860 3410);
DISPLAY INVISIBLE (860 3410);
FORCEPROP 1 LASTPIN (850 3400) BN 0
J 2
(900 3410);
DISPLAY 0.617021 (900 3410);
PAINT PINK (900 3410);
FORCEPROP 2 LAST CDS_LIB mstr_standard
J 0
(900 3400);
DISPLAY 0.787234 (900 3400);
PAINT MONO (900 3400);
DISPLAY INVISIBLE (900 3400);
FORCEPROP 1 LAST BODY_TYPE PLUMBING
J 2
(900 3350);
DISPLAY 1.234043 (900 3350);
PAINT GREEN (900 3350);
DISPLAY INVISIBLE (900 3350);
FORCEPROP 1 LAST HDL_TAP TRUE
J 2
(575 3275);
DISPLAY 1.234043 (575 3275);
PAINT GREEN (575 3275);
DISPLAY INVISIBLE (575 3275);
FORCEPROP 1 LAST PATH I23
J 2
(900 3400);
DISPLAY 0.936170 (900 3400);
PAINT GREEN (900 3400);
DISPLAY INVISIBLE (900 3400);
FORCEADD SCONN288_H44441003..3
(1800 2400);
FORCEPROP 1 LAST PART_NUMBER H44441-003
J 0
(1350 1050);
DISPLAY 0.617021 (1350 1050);
PAINT BLUE (1350 1050);
FORCEPROP 1 LAST MATERIAL SCONN
J 0
(1350 3750);
DISPLAY 0.617021 (1350 3750);
PAINT SKYBLUE (1350 3750);
FORCEPROP 2 LASTPIN (1300 3550) $PN 2
J 2
(1290 3560);
DISPLAY 0.617021 (1290 3560);
PAINT ORANGE (1290 3560);
FORCEPROP 2 LASTPIN (1300 3500) $PN 4
J 2
(1290 3510);
DISPLAY 0.617021 (1290 3510);
PAINT ORANGE (1290 3510);
FORCEPROP 2 LASTPIN (1300 3300) $PN 13
J 2
(1290 3310);
DISPLAY 0.617021 (1290 3310);
PAINT ORANGE (1290 3310);
FORCEPROP 2 LASTPIN (1300 3200) $PN 17
J 2
(1290 3210);
DISPLAY 0.617021 (1290 3210);
PAINT ORANGE (1290 3210);
FORCEPROP 2 LASTPIN (1300 3150) $PN 20
J 2
(1290 3160);
DISPLAY 0.617021 (1290 3160);
PAINT ORANGE (1290 3160);
FORCEPROP 2 LASTPIN (1300 3100) $PN 22
J 2
(1290 3110);
DISPLAY 0.617021 (1290 3110);
PAINT ORANGE (1290 3110);
FORCEPROP 2 LASTPIN (1300 3000) $PN 26
J 2
(1290 3010);
DISPLAY 0.617021 (1290 3010);
PAINT ORANGE (1290 3010);
FORCEPROP 2 LASTPIN (1300 2950) $PN 28
J 2
(1290 2960);
DISPLAY 0.617021 (1290 2960);
PAINT ORANGE (1290 2960);
FORCEPROP 2 LASTPIN (1300 2900) $PN 31
J 2
(1290 2910);
DISPLAY 0.617021 (1290 2910);
PAINT ORANGE (1290 2910);
FORCEPROP 2 LASTPIN (1300 2850) $PN 33
J 2
(1290 2860);
DISPLAY 0.617021 (1290 2860);
PAINT ORANGE (1290 2860);
FORCEPROP 2 LASTPIN (1300 2800) $PN 35
J 2
(1290 2810);
DISPLAY 0.617021 (1290 2810);
PAINT ORANGE (1290 2810);
FORCEPROP 2 LASTPIN (1300 2750) $PN 37
J 2
(1290 2760);
DISPLAY 0.617021 (1290 2760);
PAINT ORANGE (1290 2760);
FORCEPROP 2 LASTPIN (1300 2700) $PN 39
J 2
(1290 2710);
DISPLAY 0.617021 (1290 2710);
PAINT ORANGE (1290 2710);
FORCEPROP 2 LASTPIN (1300 2650) $PN 42
J 2
(1290 2660);
DISPLAY 0.617021 (1290 2660);
PAINT ORANGE (1290 2660);
FORCEPROP 2 LASTPIN (1300 2600) $PN 44
J 2
(1290 2610);
DISPLAY 0.617021 (1290 2610);
PAINT ORANGE (1290 2610);
FORCEPROP 2 LASTPIN (1300 2550) $PN 46
J 2
(1290 2560);
DISPLAY 0.617021 (1290 2560);
PAINT ORANGE (1290 2560);
FORCEPROP 2 LASTPIN (1300 2500) $PN 48
J 2
(1290 2510);
DISPLAY 0.617021 (1290 2510);
PAINT ORANGE (1290 2510);
FORCEPROP 2 LASTPIN (1300 2450) $PN 50
J 2
(1290 2460);
DISPLAY 0.617021 (1290 2460);
PAINT ORANGE (1290 2460);
FORCEPROP 2 LASTPIN (1300 2400) $PN 53
J 2
(1290 2410);
DISPLAY 0.617021 (1290 2410);
PAINT ORANGE (1290 2410);
FORCEPROP 2 LASTPIN (1300 2350) $PN 55
J 2
(1290 2360);
DISPLAY 0.617021 (1290 2360);
PAINT ORANGE (1290 2360);
FORCEPROP 2 LASTPIN (1300 2300) $PN 57
J 2
(1290 2310);
DISPLAY 0.617021 (1290 2310);
PAINT ORANGE (1290 2310);
FORCEPROP 2 LASTPIN (1300 2250) $PN 94
J 2
(1290 2260);
DISPLAY 0.617021 (1290 2260);
PAINT ORANGE (1290 2260);
FORCEPROP 2 LASTPIN (1300 2200) $PN 96
J 2
(1290 2210);
DISPLAY 0.617021 (1290 2210);
PAINT ORANGE (1290 2210);
FORCEPROP 2 LASTPIN (1300 2150) $PN 98
J 2
(1290 2160);
DISPLAY 0.617021 (1290 2160);
PAINT ORANGE (1290 2160);
FORCEPROP 2 LASTPIN (1300 2100) $PN 101
J 2
(1290 2110);
DISPLAY 0.617021 (1290 2110);
PAINT ORANGE (1290 2110);
FORCEPROP 2 LASTPIN (1300 2050) $PN 103
J 2
(1290 2060);
DISPLAY 0.617021 (1290 2060);
PAINT ORANGE (1290 2060);
FORCEPROP 2 LASTPIN (1300 1900) $PN 109
J 2
(1290 1910);
DISPLAY 0.617021 (1290 1910);
PAINT ORANGE (1290 1910);
FORCEPROP 2 LASTPIN (1300 1850) $PN 112
J 2
(1290 1860);
DISPLAY 0.617021 (1290 1860);
PAINT ORANGE (1290 1860);
FORCEPROP 2 LASTPIN (1300 1800) $PN 114
J 2
(1290 1810);
DISPLAY 0.617021 (1290 1810);
PAINT ORANGE (1290 1810);
FORCEPROP 2 LASTPIN (1300 1750) $PN 116
J 2
(1290 1760);
DISPLAY 0.617021 (1290 1760);
PAINT ORANGE (1290 1760);
FORCEPROP 2 LASTPIN (1300 1700) $PN 118
J 2
(1290 1710);
DISPLAY 0.617021 (1290 1710);
PAINT ORANGE (1290 1710);
FORCEPROP 2 LASTPIN (1300 1650) $PN 120
J 2
(1290 1660);
DISPLAY 0.617021 (1290 1660);
PAINT ORANGE (1290 1660);
FORCEPROP 2 LASTPIN (1300 1600) $PN 123
J 2
(1290 1610);
DISPLAY 0.617021 (1290 1610);
PAINT ORANGE (1290 1610);
FORCEPROP 2 LASTPIN (1300 1550) $PN 125
J 2
(1290 1560);
DISPLAY 0.617021 (1290 1560);
PAINT ORANGE (1290 1560);
FORCEPROP 2 LASTPIN (1300 1450) $PN 129
J 2
(1290 1460);
DISPLAY 0.617021 (1290 1460);
PAINT ORANGE (1290 1460);
FORCEPROP 2 LASTPIN (1300 1400) $PN 131
J 2
(1290 1410);
DISPLAY 0.617021 (1290 1410);
PAINT ORANGE (1290 1410);
FORCEPROP 2 LASTPIN (1300 1350) $PN 134
J 2
(1290 1360);
DISPLAY 0.617021 (1290 1360);
PAINT ORANGE (1290 1360);
FORCEPROP 2 LASTPIN (1300 1300) $PN 136
J 2
(1290 1310);
DISPLAY 0.617021 (1290 1310);
PAINT ORANGE (1290 1310);
FORCEPROP 2 LASTPIN (1300 1250) $PN 138
J 2
(1290 1260);
DISPLAY 0.617021 (1290 1260);
PAINT ORANGE (1290 1260);
FORCEPROP 2 LASTPIN (2300 3550) $PN 147
J 0
(2310 3560);
DISPLAY 0.617021 (2310 3560);
PAINT ORANGE (2310 3560);
FORCEPROP 2 LASTPIN (2300 3500) $PN 149
J 0
(2310 3510);
DISPLAY 0.617021 (2310 3510);
PAINT ORANGE (2310 3510);
FORCEPROP 2 LASTPIN (2300 3450) $PN 151
J 0
(2310 3460);
DISPLAY 0.617021 (2310 3460);
PAINT ORANGE (2310 3460);
FORCEPROP 2 LASTPIN (2300 3400) $PN 154
J 0
(2310 3410);
DISPLAY 0.617021 (2310 3410);
PAINT ORANGE (2310 3410);
FORCEPROP 2 LASTPIN (2300 3350) $PN 156
J 0
(2310 3360);
DISPLAY 0.617021 (2310 3360);
PAINT ORANGE (2310 3360);
FORCEPROP 2 LASTPIN (2300 3300) $PN 158
J 0
(2310 3310);
DISPLAY 0.617021 (2310 3310);
PAINT ORANGE (2310 3310);
FORCEPROP 2 LASTPIN (2300 3250) $PN 160
J 0
(2310 3260);
DISPLAY 0.617021 (2310 3260);
PAINT ORANGE (2310 3260);
FORCEPROP 2 LASTPIN (2300 3200) $PN 162
J 0
(2310 3210);
DISPLAY 0.617021 (2310 3210);
PAINT ORANGE (2310 3210);
FORCEPROP 2 LASTPIN (2300 3150) $PN 165
J 0
(2310 3160);
DISPLAY 0.617021 (2310 3160);
PAINT ORANGE (2310 3160);
FORCEPROP 2 LASTPIN (2300 3100) $PN 167
J 0
(2310 3110);
DISPLAY 0.617021 (2310 3110);
PAINT ORANGE (2310 3110);
FORCEPROP 2 LASTPIN (2300 3050) $PN 169
J 0
(2310 3060);
DISPLAY 0.617021 (2310 3060);
PAINT ORANGE (2310 3060);
FORCEPROP 2 LASTPIN (2300 3000) $PN 171
J 0
(2310 3010);
DISPLAY 0.617021 (2310 3010);
PAINT ORANGE (2310 3010);
FORCEPROP 2 LASTPIN (2300 2950) $PN 173
J 0
(2310 2960);
DISPLAY 0.617021 (2310 2960);
PAINT ORANGE (2310 2960);
FORCEPROP 2 LASTPIN (2300 2900) $PN 176
J 0
(2310 2910);
DISPLAY 0.617021 (2310 2910);
PAINT ORANGE (2310 2910);
FORCEPROP 2 LASTPIN (2300 2850) $PN 178
J 0
(2310 2860);
DISPLAY 0.617021 (2310 2860);
PAINT ORANGE (2310 2860);
FORCEPROP 2 LASTPIN (2300 2800) $PN 180
J 0
(2310 2810);
DISPLAY 0.617021 (2310 2810);
PAINT ORANGE (2310 2810);
FORCEPROP 2 LASTPIN (2300 2750) $PN 182
J 0
(2310 2760);
DISPLAY 0.617021 (2310 2760);
PAINT ORANGE (2310 2760);
FORCEPROP 2 LASTPIN (2300 2700) $PN 184
J 0
(2310 2710);
DISPLAY 0.617021 (2310 2710);
PAINT ORANGE (2310 2710);
FORCEPROP 2 LASTPIN (2300 2650) $PN 187
J 0
(2310 2660);
DISPLAY 0.617021 (2310 2660);
PAINT ORANGE (2310 2660);
FORCEPROP 2 LASTPIN (2300 2600) $PN 189
J 0
(2310 2610);
DISPLAY 0.617021 (2310 2610);
PAINT ORANGE (2310 2610);
FORCEPROP 2 LASTPIN (2300 2550) $PN 191
J 0
(2310 2560);
DISPLAY 0.617021 (2310 2560);
PAINT ORANGE (2310 2560);
FORCEPROP 2 LASTPIN (2300 2500) $PN 193
J 0
(2310 2510);
DISPLAY 0.617021 (2310 2510);
PAINT ORANGE (2310 2510);
FORCEPROP 2 LASTPIN (2300 2450) $PN 195
J 0
(2310 2460);
DISPLAY 0.617021 (2310 2460);
PAINT ORANGE (2310 2460);
FORCEPROP 2 LASTPIN (2300 2400) $PN 198
J 0
(2310 2410);
DISPLAY 0.617021 (2310 2410);
PAINT ORANGE (2310 2410);
FORCEPROP 2 LASTPIN (2300 2350) $PN 200
J 0
(2310 2360);
DISPLAY 0.617021 (2310 2360);
PAINT ORANGE (2310 2360);
FORCEPROP 2 LASTPIN (2300 2300) $PN 202
J 0
(2310 2310);
DISPLAY 0.617021 (2310 2310);
PAINT ORANGE (2310 2310);
FORCEPROP 2 LASTPIN (2300 2250) $PN 239
J 0
(2310 2260);
DISPLAY 0.617021 (2310 2260);
PAINT ORANGE (2310 2260);
FORCEPROP 2 LASTPIN (2300 2200) $PN 241
J 0
(2310 2210);
DISPLAY 0.617021 (2310 2210);
PAINT ORANGE (2310 2210);
FORCEPROP 2 LASTPIN (2300 2150) $PN 243
J 0
(2310 2160);
DISPLAY 0.617021 (2310 2160);
PAINT ORANGE (2310 2160);
FORCEPROP 2 LASTPIN (2300 2000) $PN 250
J 0
(2310 2010);
DISPLAY 0.617021 (2310 2010);
PAINT ORANGE (2310 2010);
FORCEPROP 2 LASTPIN (2300 1950) $PN 252
J 0
(2310 1960);
DISPLAY 0.617021 (2310 1960);
PAINT ORANGE (2310 1960);
FORCEPROP 2 LASTPIN (2300 1900) $PN 254
J 0
(2310 1910);
DISPLAY 0.617021 (2310 1910);
PAINT ORANGE (2310 1910);
FORCEPROP 2 LASTPIN (2300 1850) $PN 257
J 0
(2310 1860);
DISPLAY 0.617021 (2310 1860);
PAINT ORANGE (2310 1860);
FORCEPROP 2 LASTPIN (2300 1800) $PN 259
J 0
(2310 1810);
DISPLAY 0.617021 (2310 1810);
PAINT ORANGE (2310 1810);
FORCEPROP 2 LASTPIN (2300 1750) $PN 261
J 0
(2310 1760);
DISPLAY 0.617021 (2310 1760);
PAINT ORANGE (2310 1760);
FORCEPROP 2 LASTPIN (2300 1700) $PN 263
J 0
(2310 1710);
DISPLAY 0.617021 (2310 1710);
PAINT ORANGE (2310 1710);
FORCEPROP 2 LASTPIN (2300 1650) $PN 265
J 0
(2310 1660);
DISPLAY 0.617021 (2310 1660);
PAINT ORANGE (2310 1660);
FORCEPROP 2 LASTPIN (2300 1600) $PN 268
J 0
(2310 1610);
DISPLAY 0.617021 (2310 1610);
PAINT ORANGE (2310 1610);
FORCEPROP 2 LASTPIN (2300 1550) $PN 270
J 0
(2310 1560);
DISPLAY 0.617021 (2310 1560);
PAINT ORANGE (2310 1560);
FORCEPROP 2 LASTPIN (2300 1450) $PN 274
J 0
(2310 1460);
DISPLAY 0.617021 (2310 1460);
PAINT ORANGE (2310 1460);
FORCEPROP 2 LASTPIN (2300 1400) $PN 276
J 0
(2310 1410);
DISPLAY 0.617021 (2310 1410);
PAINT ORANGE (2310 1410);
FORCEPROP 2 LASTPIN (2300 1350) $PN 279
J 0
(2310 1360);
DISPLAY 0.617021 (2310 1360);
PAINT ORANGE (2310 1360);
FORCEPROP 2 LASTPIN (2300 1300) $PN 281
J 0
(2310 1310);
DISPLAY 0.617021 (2310 1310);
PAINT ORANGE (2310 1310);
FORCEPROP 2 LASTPIN (2300 1250) $PN 283
J 0
(2310 1260);
DISPLAY 0.617021 (2310 1260);
PAINT ORANGE (2310 1260);
FORCEPROP 2 LASTPIN (1300 3050) $PN 24
J 2
(1290 3060);
DISPLAY 0.617021 (1290 3060);
PAINT ORANGE (1290 3060);
FORCEPROP 2 LASTPIN (2300 1500) $PN 272
J 0
(2310 1510);
DISPLAY 0.617021 (2310 1510);
PAINT ORANGE (2310 1510);
FORCEPROP 2 LASTPIN (1300 3350) $PN 11
J 2
(1290 3360);
DISPLAY 0.617021 (1290 3360);
PAINT ORANGE (1290 3360);
FORCEPROP 2 LASTPIN (1300 3400) $PN 9
J 2
(1290 3410);
DISPLAY 0.617021 (1290 3410);
PAINT ORANGE (1290 3410);
FORCEPROP 2 LASTPIN (1300 3450) $PN 6
J 2
(1290 3460);
DISPLAY 0.617021 (1290 3460);
PAINT ORANGE (1290 3460);
FORCEPROP 1 LAST LOCATION J9L1
J 0
(1350 3800);
DISPLAY 0.617021 (1350 3800);
PAINT AQUA (1350 3800);
FORCEPROP 2 LASTPIN (1300 1950) $PN 107
J 2
(1290 1960);
DISPLAY 0.617021 (1290 1960);
PAINT ORANGE (1290 1960);
FORCEPROP 2 LASTPIN (2300 2050) $PN 248
J 0
(2310 2060);
DISPLAY 0.617021 (2310 2060);
PAINT ORANGE (2310 2060);
FORCEPROP 2 LASTPIN (2300 2100) $PN 246
J 0
(2310 2110);
DISPLAY 0.617021 (2310 2110);
PAINT ORANGE (2310 2110);
FORCEPROP 2 LASTPIN (1300 3250) $PN 15
J 2
(1290 3260);
DISPLAY 0.617021 (1290 3260);
PAINT ORANGE (1290 3260);
FORCEPROP 0 LAST BOM_SS NOPOP
J 0
(1489 3917);
DISPLAY 1.021277 (1489 3917);
PAINT BROWN (1489 3917);
DISPLAY BOTH (1489 3917);
FORCEPROP 2 LASTPIN (1300 2000) $PN 105
J 2
(1290 2010);
DISPLAY 0.617021 (1290 2010);
PAINT ORANGE (1290 2010);
FORCEPROP 2 LASTPIN (1300 1500) $PN 127
J 2
(1290 1510);
DISPLAY 0.617021 (1290 1510);
PAINT ORANGE (1290 1510);
FORCEPROP 1 LAST PACK_TYPE PIP
J 0
(1350 3850);
PAINT SKYBLUE (1350 3850);
DISPLAY INVISIBLE (1350 3850);
FORCEPROP 2 LAST SEC_TYPE PIP
J 0
(1350 3850);
DISPLAY 1.021277 (1350 3850);
PAINT ORANGE (1350 3850);
DISPLAY INVISIBLE (1350 3850);
FORCEPROP 2 LAST CDS_LIB mstr_sconn
J 0
(1800 2400);
PAINT ORANGE (1800 2400);
DISPLAY INVISIBLE (1800 2400);
FORCEPROP 2 LAST BOM_COST DDR4_CH_M
J 0
(1800 2400);
PAINT ORANGE (1800 2400);
DISPLAY INVISIBLE (1800 2400);
FORCEPROP 2 LAST SEC 3
J 0
(1350 3850);
DISPLAY 0.680851 (1350 3850);
PAINT MONO (1350 3850);
DISPLAY INVISIBLE (1350 3850);
FORCEPROP 2 LAST CDS_LOCATION J9L1
J 0
(1350 3800);
DISPLAY 0.617021 (1350 3800);
PAINT AQUA (1350 3800);
DISPLAY INVISIBLE (1350 3800);
FORCEPROP 1 LAST PATH I25
J 0
(1800 3750);
PAINT GREEN (1800 3750);
DISPLAY INVISIBLE (1800 3750);
FORCEPROP 2 LAST ROOM DDR4_CH_M
J 0
(1800 2400);
PAINT ORANGE (1800 2400);
DISPLAY INVISIBLE (1800 2400);
FORCEADD GND..1
R 2
(1100 1100);
FORCEPROP 3 LASTPIN (1100 1150) SIG_NAME GND\g
J 0
(1110 1160);
DISPLAY 0.659574 (1110 1160);
PAINT MONO (1110 1160);
DISPLAY INVISIBLE (1110 1160);
FORCEPROP 1 LAST VOLTAGE 4V
J 0
(1100 1100);
PAINT SKYBLUE (1100 1100);
DISPLAY INVISIBLE (1100 1100);
FORCEPROP 1 LAST SIZE 1B
J 2
(1025 1050);
DISPLAY 1.170213 (1025 1050);
PAINT GREEN (1025 1050);
DISPLAY INVISIBLE (1025 1050);
FORCEPROP 2 LAST CDS_LIB mstr_symbols
J 0
(1100 1100);
DISPLAY 0.787234 (1100 1100);
PAINT MONO (1100 1100);
DISPLAY INVISIBLE (1100 1100);
FORCEPROP 2 LAST BOM_COST PROC
J 0
(1100 1105);
PAINT ORANGE (1100 1105);
DISPLAY INVISIBLE (1100 1105);
FORCEPROP 1 LAST BODY_TYPE PLUMBING
J 2
(1145 1057);
DISPLAY 0.340426 (1145 1057);
PAINT GREEN (1145 1057);
DISPLAY INVISIBLE (1145 1057);
FORCEPROP 1 LAST PATH I26
J 2
(1025 1100);
DISPLAY 0.936170 (1025 1100);
PAINT GREEN (1025 1100);
DISPLAY INVISIBLE (1025 1100);
FORCEPROP 2 LAST ROOM PROC
J 0
(1100 1105);
PAINT ORANGE (1100 1105);
DISPLAY INVISIBLE (1100 1105);
FORCEPROP 1 LAST HDL_POWER GND
J 2
(1100 1250);
DISPLAY 0.553191 (1100 1250);
PAINT GREEN (1100 1250);
DISPLAY INVISIBLE (1100 1250);
FORCEADD TAP..6
R 2
(700 5150);
FORCEPROP 3 LASTPIN (650 5150) SIG_NAME M_M_DQS_DP<17>
J 0
(660 5160);
DISPLAY 0.659574 (660 5160);
PAINT MONO (660 5160);
DISPLAY INVISIBLE (660 5160);
FORCEPROP 1 LASTPIN (650 5150) BN 17
J 2
(700 5160);
DISPLAY 0.617021 (700 5160);
PAINT PINK (700 5160);
FORCEPROP 2 LAST CDS_LIB mstr_standard
J 2
(700 5150);
DISPLAY 0.787234 (700 5150);
PAINT MONO (700 5150);
DISPLAY INVISIBLE (700 5150);
FORCEPROP 1 LAST BODY_TYPE PLUMBING
J 2
(700 5100);
DISPLAY 1.234043 (700 5100);
PAINT GREEN (700 5100);
DISPLAY INVISIBLE (700 5100);
FORCEPROP 1 LAST HDL_TAP TRUE
J 2
(375 5025);
DISPLAY 1.234043 (375 5025);
PAINT GREEN (375 5025);
DISPLAY INVISIBLE (375 5025);
FORCEPROP 1 LAST PATH I27
J 2
(700 5150);
DISPLAY 0.936170 (700 5150);
PAINT GREEN (700 5150);
DISPLAY INVISIBLE (700 5150);
FORCEADD TAP..6
R 2
(700 5050);
FORCEPROP 3 LASTPIN (650 5050) SIG_NAME M_M_DQS_DP<16>
J 0
(660 5060);
DISPLAY 0.659574 (660 5060);
PAINT MONO (660 5060);
DISPLAY INVISIBLE (660 5060);
FORCEPROP 1 LASTPIN (650 5050) BN 16
J 2
(700 5060);
DISPLAY 0.617021 (700 5060);
PAINT PINK (700 5060);
FORCEPROP 2 LAST CDS_LIB mstr_standard
J 0
(700 5050);
DISPLAY 0.787234 (700 5050);
PAINT MONO (700 5050);
DISPLAY INVISIBLE (700 5050);
FORCEPROP 1 LAST BODY_TYPE PLUMBING
J 2
(700 5000);
DISPLAY 1.234043 (700 5000);
PAINT GREEN (700 5000);
DISPLAY INVISIBLE (700 5000);
FORCEPROP 1 LAST HDL_TAP TRUE
J 2
(375 4925);
DISPLAY 1.234043 (375 4925);
PAINT GREEN (375 4925);
DISPLAY INVISIBLE (375 4925);
FORCEPROP 1 LAST PATH I28
J 2
(700 5050);
DISPLAY 0.936170 (700 5050);
PAINT GREEN (700 5050);
DISPLAY INVISIBLE (700 5050);
FORCEADD TAP..6
R 2
(700 4750);
FORCEPROP 3 LASTPIN (650 4750) SIG_NAME M_M_DQS_DP<13>
J 0
(660 4760);
DISPLAY 0.659574 (660 4760);
PAINT MONO (660 4760);
DISPLAY INVISIBLE (660 4760);
FORCEPROP 1 LASTPIN (650 4750) BN 13
J 2
(700 4760);
DISPLAY 0.617021 (700 4760);
PAINT PINK (700 4760);
FORCEPROP 2 LAST CDS_LIB mstr_standard
J 0
(700 4750);
DISPLAY 0.787234 (700 4750);
PAINT MONO (700 4750);
DISPLAY INVISIBLE (700 4750);
FORCEPROP 1 LAST BODY_TYPE PLUMBING
J 2
(700 4700);
DISPLAY 1.234043 (700 4700);
PAINT GREEN (700 4700);
DISPLAY INVISIBLE (700 4700);
FORCEPROP 1 LAST HDL_TAP TRUE
J 2
(375 4625);
DISPLAY 1.234043 (375 4625);
PAINT GREEN (375 4625);
DISPLAY INVISIBLE (375 4625);
FORCEPROP 1 LAST PATH I29
J 2
(700 4750);
DISPLAY 0.936170 (700 4750);
PAINT GREEN (700 4750);
DISPLAY INVISIBLE (700 4750);
FORCEADD TAP..6
R 2
(900 5100);
FORCEPROP 3 LASTPIN (850 5100) SIG_NAME M_M_DQS_DN<17>
J 0
(860 5110);
DISPLAY 0.659574 (860 5110);
PAINT MONO (860 5110);
DISPLAY INVISIBLE (860 5110);
FORCEPROP 1 LASTPIN (850 5100) BN 17
J 2
(900 5110);
DISPLAY 0.617021 (900 5110);
PAINT PINK (900 5110);
FORCEPROP 2 LAST CDS_LIB mstr_standard
J 2
(900 5100);
DISPLAY 0.787234 (900 5100);
PAINT MONO (900 5100);
DISPLAY INVISIBLE (900 5100);
FORCEPROP 1 LAST BODY_TYPE PLUMBING
J 2
(900 5050);
DISPLAY 1.234043 (900 5050);
PAINT GREEN (900 5050);
DISPLAY INVISIBLE (900 5050);
FORCEPROP 1 LAST HDL_TAP TRUE
J 2
(575 4975);
DISPLAY 1.234043 (575 4975);
PAINT GREEN (575 4975);
DISPLAY INVISIBLE (575 4975);
FORCEPROP 1 LAST PATH I3
J 2
(900 5100);
DISPLAY 0.936170 (900 5100);
PAINT GREEN (900 5100);
DISPLAY INVISIBLE (900 5100);
FORCEADD TAP..6
R 2
(700 4650);
FORCEPROP 3 LASTPIN (650 4650) SIG_NAME M_M_DQS_DP<12>
J 0
(660 4660);
DISPLAY 0.659574 (660 4660);
PAINT MONO (660 4660);
DISPLAY INVISIBLE (660 4660);
FORCEPROP 1 LASTPIN (650 4650) BN 12
J 2
(700 4660);
DISPLAY 0.617021 (700 4660);
PAINT PINK (700 4660);
FORCEPROP 2 LAST CDS_LIB mstr_standard
J 0
(700 4650);
DISPLAY 0.787234 (700 4650);
PAINT MONO (700 4650);
DISPLAY INVISIBLE (700 4650);
FORCEPROP 1 LAST BODY_TYPE PLUMBING
J 2
(700 4600);
DISPLAY 1.234043 (700 4600);
PAINT GREEN (700 4600);
DISPLAY INVISIBLE (700 4600);
FORCEPROP 1 LAST HDL_TAP TRUE
J 2
(375 4525);
DISPLAY 1.234043 (375 4525);
PAINT GREEN (375 4525);
DISPLAY INVISIBLE (375 4525);
FORCEPROP 1 LAST PATH I30
J 2
(700 4650);
DISPLAY 0.936170 (700 4650);
PAINT GREEN (700 4650);
DISPLAY INVISIBLE (700 4650);
FORCEADD TAP..6
R 2
(700 4550);
FORCEPROP 3 LASTPIN (650 4550) SIG_NAME M_M_DQS_DP<11>
J 0
(660 4560);
DISPLAY 0.659574 (660 4560);
PAINT MONO (660 4560);
DISPLAY INVISIBLE (660 4560);
FORCEPROP 1 LASTPIN (650 4550) BN 11
J 2
(700 4560);
DISPLAY 0.617021 (700 4560);
PAINT PINK (700 4560);
FORCEPROP 2 LAST CDS_LIB mstr_standard
J 0
(700 4550);
DISPLAY 0.787234 (700 4550);
PAINT MONO (700 4550);
DISPLAY INVISIBLE (700 4550);
FORCEPROP 1 LAST BODY_TYPE PLUMBING
J 2
(700 4500);
DISPLAY 1.234043 (700 4500);
PAINT GREEN (700 4500);
DISPLAY INVISIBLE (700 4500);
FORCEPROP 1 LAST HDL_TAP TRUE
J 2
(375 4425);
DISPLAY 1.234043 (375 4425);
PAINT GREEN (375 4425);
DISPLAY INVISIBLE (375 4425);
FORCEPROP 1 LAST PATH I31
J 2
(700 4550);
DISPLAY 0.936170 (700 4550);
PAINT GREEN (700 4550);
DISPLAY INVISIBLE (700 4550);
FORCEADD TAP..6
R 2
(700 4950);
FORCEPROP 3 LASTPIN (650 4950) SIG_NAME M_M_DQS_DP<15>
J 0
(660 4960);
DISPLAY 0.659574 (660 4960);
PAINT MONO (660 4960);
DISPLAY INVISIBLE (660 4960);
FORCEPROP 1 LASTPIN (650 4950) BN 15
J 2
(700 4960);
DISPLAY 0.617021 (700 4960);
PAINT PINK (700 4960);
FORCEPROP 2 LAST CDS_LIB mstr_standard
J 0
(700 4950);
DISPLAY 0.787234 (700 4950);
PAINT MONO (700 4950);
DISPLAY INVISIBLE (700 4950);
FORCEPROP 1 LAST BODY_TYPE PLUMBING
J 2
(700 4900);
DISPLAY 1.234043 (700 4900);
PAINT GREEN (700 4900);
DISPLAY INVISIBLE (700 4900);
FORCEPROP 1 LAST HDL_TAP TRUE
J 2
(375 4825);
DISPLAY 1.234043 (375 4825);
PAINT GREEN (375 4825);
DISPLAY INVISIBLE (375 4825);
FORCEPROP 1 LAST PATH I32
J 2
(700 4950);
DISPLAY 0.936170 (700 4950);
PAINT GREEN (700 4950);
DISPLAY INVISIBLE (700 4950);
FORCEADD TAP..6
R 2
(700 4850);
FORCEPROP 3 LASTPIN (650 4850) SIG_NAME M_M_DQS_DP<14>
J 0
(660 4860);
DISPLAY 0.659574 (660 4860);
PAINT MONO (660 4860);
DISPLAY INVISIBLE (660 4860);
FORCEPROP 1 LASTPIN (650 4850) BN 14
J 2
(700 4860);
DISPLAY 0.617021 (700 4860);
PAINT PINK (700 4860);
FORCEPROP 2 LAST CDS_LIB mstr_standard
J 0
(700 4850);
DISPLAY 0.787234 (700 4850);
PAINT MONO (700 4850);
DISPLAY INVISIBLE (700 4850);
FORCEPROP 1 LAST BODY_TYPE PLUMBING
J 2
(700 4800);
DISPLAY 1.234043 (700 4800);
PAINT GREEN (700 4800);
DISPLAY INVISIBLE (700 4800);
FORCEPROP 1 LAST HDL_TAP TRUE
J 2
(375 4725);
DISPLAY 1.234043 (375 4725);
PAINT GREEN (375 4725);
DISPLAY INVISIBLE (375 4725);
FORCEPROP 1 LAST PATH I33
J 2
(700 4850);
DISPLAY 0.936170 (700 4850);
PAINT GREEN (700 4850);
DISPLAY INVISIBLE (700 4850);
FORCEADD OFFPAGE..3
(-1150 4800);
FORCEPROP 2 LAST $XR1 87 
J 0
(-846 4800);
DISPLAY 0.638298 (-846 4800);
PAINT MONO (-846 4800);
FORCEPROP 2 LAST $XR0 62 
J 0
(-936 4800);
DISPLAY 0.638298 (-936 4800);
PAINT MONO (-936 4800);
FORCEPROP 2 LAST CDS_LIB mstr_standard
J 0
(-1150 4800);
DISPLAY 0.787234 (-1150 4800);
PAINT MONO (-1150 4800);
DISPLAY INVISIBLE (-1150 4800);
FORCEPROP 1 LAST OFFPAGE TRUE
J 0
(-825 4675);
DISPLAY 0.936170 (-825 4675);
PAINT GREEN (-825 4675);
DISPLAY INVISIBLE (-825 4675);
FORCEPROP 1 LAST COMMENT_BODY TRUE
J 0
(-1200 4700);
DISPLAY 0.936170 (-1200 4700);
PAINT GREEN (-1200 4700);
DISPLAY INVISIBLE (-1200 4700);
FORCEPROP 2 LAST PATH I34
J 0
(-950 4875);
DISPLAY 0.787234 (-950 4875);
PAINT MONO (-950 4875);
DISPLAY INVISIBLE (-950 4875);
FORCEADD TAP..6
R 2
(-1700 4550);
FORCEPROP 3 LASTPIN (-1750 4550) SIG_NAME M_M_DQ<59>
J 0
(-1740 4560);
DISPLAY 0.659574 (-1740 4560);
PAINT MONO (-1740 4560);
DISPLAY INVISIBLE (-1740 4560);
FORCEPROP 1 LASTPIN (-1750 4550) BN 59
J 2
(-1700 4560);
DISPLAY 0.617021 (-1700 4560);
PAINT PINK (-1700 4560);
FORCEPROP 2 LAST CDS_LIB mstr_standard
J 2
(-1700 4550);
DISPLAY 0.787234 (-1700 4550);
PAINT MONO (-1700 4550);
DISPLAY INVISIBLE (-1700 4550);
FORCEPROP 1 LAST BODY_TYPE PLUMBING
J 2
(-1700 4500);
DISPLAY 1.234043 (-1700 4500);
PAINT GREEN (-1700 4500);
DISPLAY INVISIBLE (-1700 4500);
FORCEPROP 1 LAST HDL_TAP TRUE
J 2
(-2025 4425);
DISPLAY 1.234043 (-2025 4425);
PAINT GREEN (-2025 4425);
DISPLAY INVISIBLE (-2025 4425);
FORCEPROP 1 LAST PATH I35
J 2
(-1700 4550);
DISPLAY 0.936170 (-1700 4550);
PAINT GREEN (-1700 4550);
DISPLAY INVISIBLE (-1700 4550);
FORCEADD TAP..6
R 2
(-1700 4750);
FORCEPROP 3 LASTPIN (-1750 4750) SIG_NAME M_M_DQ<63>
J 0
(-1740 4760);
DISPLAY 0.659574 (-1740 4760);
PAINT MONO (-1740 4760);
DISPLAY INVISIBLE (-1740 4760);
FORCEPROP 1 LASTPIN (-1750 4750) BN 63
J 2
(-1700 4760);
DISPLAY 0.617021 (-1700 4760);
PAINT PINK (-1700 4760);
FORCEPROP 2 LAST CDS_LIB mstr_standard
J 2
(-1700 4750);
DISPLAY 0.787234 (-1700 4750);
PAINT MONO (-1700 4750);
DISPLAY INVISIBLE (-1700 4750);
FORCEPROP 1 LAST BODY_TYPE PLUMBING
J 2
(-1700 4700);
DISPLAY 1.234043 (-1700 4700);
PAINT GREEN (-1700 4700);
DISPLAY INVISIBLE (-1700 4700);
FORCEPROP 1 LAST HDL_TAP TRUE
J 2
(-2025 4625);
DISPLAY 1.234043 (-2025 4625);
PAINT GREEN (-2025 4625);
DISPLAY INVISIBLE (-2025 4625);
FORCEPROP 1 LAST PATH I36
J 2
(-1700 4750);
DISPLAY 0.936170 (-1700 4750);
PAINT GREEN (-1700 4750);
DISPLAY INVISIBLE (-1700 4750);
FORCEADD TAP..6
R 2
(-1700 4700);
FORCEPROP 3 LASTPIN (-1750 4700) SIG_NAME M_M_DQ<62>
J 0
(-1740 4710);
DISPLAY 0.659574 (-1740 4710);
PAINT MONO (-1740 4710);
DISPLAY INVISIBLE (-1740 4710);
FORCEPROP 1 LASTPIN (-1750 4700) BN 62
J 2
(-1700 4710);
DISPLAY 0.617021 (-1700 4710);
PAINT PINK (-1700 4710);
FORCEPROP 2 LAST CDS_LIB mstr_standard
J 2
(-1700 4700);
DISPLAY 0.787234 (-1700 4700);
PAINT MONO (-1700 4700);
DISPLAY INVISIBLE (-1700 4700);
FORCEPROP 1 LAST BODY_TYPE PLUMBING
J 2
(-1700 4650);
DISPLAY 1.234043 (-1700 4650);
PAINT GREEN (-1700 4650);
DISPLAY INVISIBLE (-1700 4650);
FORCEPROP 1 LAST HDL_TAP TRUE
J 2
(-2025 4575);
DISPLAY 1.234043 (-2025 4575);
PAINT GREEN (-2025 4575);
DISPLAY INVISIBLE (-2025 4575);
FORCEPROP 1 LAST PATH I37
J 2
(-1700 4700);
DISPLAY 0.936170 (-1700 4700);
PAINT GREEN (-1700 4700);
DISPLAY INVISIBLE (-1700 4700);
FORCEADD TAP..6
R 2
(-1700 4650);
FORCEPROP 3 LASTPIN (-1750 4650) SIG_NAME M_M_DQ<61>
J 0
(-1740 4660);
DISPLAY 0.659574 (-1740 4660);
PAINT MONO (-1740 4660);
DISPLAY INVISIBLE (-1740 4660);
FORCEPROP 1 LASTPIN (-1750 4650) BN 61
J 2
(-1700 4660);
DISPLAY 0.617021 (-1700 4660);
PAINT PINK (-1700 4660);
FORCEPROP 2 LAST CDS_LIB mstr_standard
J 2
(-1700 4650);
DISPLAY 0.787234 (-1700 4650);
PAINT MONO (-1700 4650);
DISPLAY INVISIBLE (-1700 4650);
FORCEPROP 1 LAST BODY_TYPE PLUMBING
J 2
(-1700 4600);
DISPLAY 1.234043 (-1700 4600);
PAINT GREEN (-1700 4600);
DISPLAY INVISIBLE (-1700 4600);
FORCEPROP 1 LAST HDL_TAP TRUE
J 2
(-2025 4525);
DISPLAY 1.234043 (-2025 4525);
PAINT GREEN (-2025 4525);
DISPLAY INVISIBLE (-2025 4525);
FORCEPROP 1 LAST PATH I38
J 2
(-1700 4650);
DISPLAY 0.936170 (-1700 4650);
PAINT GREEN (-1700 4650);
DISPLAY INVISIBLE (-1700 4650);
FORCEADD TAP..6
R 2
(-1700 4600);
FORCEPROP 3 LASTPIN (-1750 4600) SIG_NAME M_M_DQ<60>
J 0
(-1740 4610);
DISPLAY 0.659574 (-1740 4610);
PAINT MONO (-1740 4610);
DISPLAY INVISIBLE (-1740 4610);
FORCEPROP 1 LASTPIN (-1750 4600) BN 60
J 2
(-1700 4610);
DISPLAY 0.617021 (-1700 4610);
PAINT PINK (-1700 4610);
FORCEPROP 2 LAST CDS_LIB mstr_standard
J 2
(-1700 4600);
DISPLAY 0.787234 (-1700 4600);
PAINT MONO (-1700 4600);
DISPLAY INVISIBLE (-1700 4600);
FORCEPROP 1 LAST BODY_TYPE PLUMBING
J 2
(-1700 4550);
DISPLAY 1.234043 (-1700 4550);
PAINT GREEN (-1700 4550);
DISPLAY INVISIBLE (-1700 4550);
FORCEPROP 1 LAST HDL_TAP TRUE
J 2
(-2025 4475);
DISPLAY 1.234043 (-2025 4475);
PAINT GREEN (-2025 4475);
DISPLAY INVISIBLE (-2025 4475);
FORCEPROP 1 LAST PATH I39
J 2
(-1700 4600);
DISPLAY 0.936170 (-1700 4600);
PAINT GREEN (-1700 4600);
DISPLAY INVISIBLE (-1700 4600);
FORCEADD TAP..6
R 2
(900 5000);
FORCEPROP 3 LASTPIN (850 5000) SIG_NAME M_M_DQS_DN<16>
J 0
(860 5010);
DISPLAY 0.659574 (860 5010);
PAINT MONO (860 5010);
DISPLAY INVISIBLE (860 5010);
FORCEPROP 1 LASTPIN (850 5000) BN 16
J 2
(900 5010);
DISPLAY 0.617021 (900 5010);
PAINT PINK (900 5010);
FORCEPROP 2 LAST CDS_LIB mstr_standard
J 0
(900 5000);
DISPLAY 0.787234 (900 5000);
PAINT MONO (900 5000);
DISPLAY INVISIBLE (900 5000);
FORCEPROP 1 LAST BODY_TYPE PLUMBING
J 2
(900 4950);
DISPLAY 1.234043 (900 4950);
PAINT GREEN (900 4950);
DISPLAY INVISIBLE (900 4950);
FORCEPROP 1 LAST HDL_TAP TRUE
J 2
(575 4875);
DISPLAY 1.234043 (575 4875);
PAINT GREEN (575 4875);
DISPLAY INVISIBLE (575 4875);
FORCEPROP 1 LAST PATH I4
J 2
(900 5000);
DISPLAY 0.936170 (900 5000);
PAINT GREEN (900 5000);
DISPLAY INVISIBLE (900 5000);
FORCEADD TAP..6
R 2
(-1700 4300);
FORCEPROP 3 LASTPIN (-1750 4300) SIG_NAME M_M_DQ<54>
J 0
(-1740 4310);
DISPLAY 0.659574 (-1740 4310);
PAINT MONO (-1740 4310);
DISPLAY INVISIBLE (-1740 4310);
FORCEPROP 1 LASTPIN (-1750 4300) BN 54
J 2
(-1700 4310);
DISPLAY 0.617021 (-1700 4310);
PAINT PINK (-1700 4310);
FORCEPROP 2 LAST CDS_LIB mstr_standard
J 2
(-1700 4300);
DISPLAY 0.787234 (-1700 4300);
PAINT MONO (-1700 4300);
DISPLAY INVISIBLE (-1700 4300);
FORCEPROP 1 LAST BODY_TYPE PLUMBING
J 2
(-1700 4250);
DISPLAY 1.234043 (-1700 4250);
PAINT GREEN (-1700 4250);
DISPLAY INVISIBLE (-1700 4250);
FORCEPROP 1 LAST HDL_TAP TRUE
J 2
(-2025 4175);
DISPLAY 1.234043 (-2025 4175);
PAINT GREEN (-2025 4175);
DISPLAY INVISIBLE (-2025 4175);
FORCEPROP 1 LAST PATH I40
J 2
(-1700 4300);
DISPLAY 0.936170 (-1700 4300);
PAINT GREEN (-1700 4300);
DISPLAY INVISIBLE (-1700 4300);
FORCEADD TAP..6
R 2
(-1700 4450);
FORCEPROP 3 LASTPIN (-1750 4450) SIG_NAME M_M_DQ<57>
J 0
(-1740 4460);
DISPLAY 0.659574 (-1740 4460);
PAINT MONO (-1740 4460);
DISPLAY INVISIBLE (-1740 4460);
FORCEPROP 1 LASTPIN (-1750 4450) BN 57
J 2
(-1700 4460);
DISPLAY 0.617021 (-1700 4460);
PAINT PINK (-1700 4460);
FORCEPROP 2 LAST CDS_LIB mstr_standard
J 2
(-1700 4450);
DISPLAY 0.787234 (-1700 4450);
PAINT MONO (-1700 4450);
DISPLAY INVISIBLE (-1700 4450);
FORCEPROP 1 LAST BODY_TYPE PLUMBING
J 2
(-1700 4400);
DISPLAY 1.234043 (-1700 4400);
PAINT GREEN (-1700 4400);
DISPLAY INVISIBLE (-1700 4400);
FORCEPROP 1 LAST HDL_TAP TRUE
J 2
(-2025 4325);
DISPLAY 1.234043 (-2025 4325);
PAINT GREEN (-2025 4325);
DISPLAY INVISIBLE (-2025 4325);
FORCEPROP 1 LAST PATH I41
J 2
(-1700 4450);
DISPLAY 0.936170 (-1700 4450);
PAINT GREEN (-1700 4450);
DISPLAY INVISIBLE (-1700 4450);
FORCEADD TAP..6
R 2
(-1700 4500);
FORCEPROP 3 LASTPIN (-1750 4500) SIG_NAME M_M_DQ<58>
J 0
(-1740 4510);
DISPLAY 0.659574 (-1740 4510);
PAINT MONO (-1740 4510);
DISPLAY INVISIBLE (-1740 4510);
FORCEPROP 1 LASTPIN (-1750 4500) BN 58
J 2
(-1700 4510);
DISPLAY 0.617021 (-1700 4510);
PAINT PINK (-1700 4510);
FORCEPROP 2 LAST CDS_LIB mstr_standard
J 2
(-1700 4500);
DISPLAY 0.787234 (-1700 4500);
PAINT MONO (-1700 4500);
DISPLAY INVISIBLE (-1700 4500);
FORCEPROP 1 LAST BODY_TYPE PLUMBING
J 2
(-1700 4450);
DISPLAY 1.234043 (-1700 4450);
PAINT GREEN (-1700 4450);
DISPLAY INVISIBLE (-1700 4450);
FORCEPROP 1 LAST HDL_TAP TRUE
J 2
(-2025 4375);
DISPLAY 1.234043 (-2025 4375);
PAINT GREEN (-2025 4375);
DISPLAY INVISIBLE (-2025 4375);
FORCEPROP 1 LAST PATH I42
J 2
(-1700 4500);
DISPLAY 0.936170 (-1700 4500);
PAINT GREEN (-1700 4500);
DISPLAY INVISIBLE (-1700 4500);
FORCEADD TAP..6
R 2
(-1700 4350);
FORCEPROP 3 LASTPIN (-1750 4350) SIG_NAME M_M_DQ<55>
J 0
(-1740 4360);
DISPLAY 0.659574 (-1740 4360);
PAINT MONO (-1740 4360);
DISPLAY INVISIBLE (-1740 4360);
FORCEPROP 1 LASTPIN (-1750 4350) BN 55
J 2
(-1700 4360);
DISPLAY 0.617021 (-1700 4360);
PAINT PINK (-1700 4360);
FORCEPROP 2 LAST CDS_LIB mstr_standard
J 2
(-1700 4350);
DISPLAY 0.787234 (-1700 4350);
PAINT MONO (-1700 4350);
DISPLAY INVISIBLE (-1700 4350);
FORCEPROP 1 LAST BODY_TYPE PLUMBING
J 2
(-1700 4300);
DISPLAY 1.234043 (-1700 4300);
PAINT GREEN (-1700 4300);
DISPLAY INVISIBLE (-1700 4300);
FORCEPROP 1 LAST HDL_TAP TRUE
J 2
(-2025 4225);
DISPLAY 1.234043 (-2025 4225);
PAINT GREEN (-2025 4225);
DISPLAY INVISIBLE (-2025 4225);
FORCEPROP 1 LAST PATH I43
J 2
(-1700 4350);
DISPLAY 0.936170 (-1700 4350);
PAINT GREEN (-1700 4350);
DISPLAY INVISIBLE (-1700 4350);
FORCEADD TAP..6
R 2
(-1700 4400);
FORCEPROP 3 LASTPIN (-1750 4400) SIG_NAME M_M_DQ<56>
J 0
(-1740 4410);
DISPLAY 0.659574 (-1740 4410);
PAINT MONO (-1740 4410);
DISPLAY INVISIBLE (-1740 4410);
FORCEPROP 1 LASTPIN (-1750 4400) BN 56
J 2
(-1700 4410);
DISPLAY 0.617021 (-1700 4410);
PAINT PINK (-1700 4410);
FORCEPROP 2 LAST CDS_LIB mstr_standard
J 2
(-1700 4400);
DISPLAY 0.787234 (-1700 4400);
PAINT MONO (-1700 4400);
DISPLAY INVISIBLE (-1700 4400);
FORCEPROP 1 LAST BODY_TYPE PLUMBING
J 2
(-1700 4350);
DISPLAY 1.234043 (-1700 4350);
PAINT GREEN (-1700 4350);
DISPLAY INVISIBLE (-1700 4350);
FORCEPROP 1 LAST HDL_TAP TRUE
J 2
(-2025 4275);
DISPLAY 1.234043 (-2025 4275);
PAINT GREEN (-2025 4275);
DISPLAY INVISIBLE (-2025 4275);
FORCEPROP 1 LAST PATH I44
J 2
(-1700 4400);
DISPLAY 0.936170 (-1700 4400);
PAINT GREEN (-1700 4400);
DISPLAY INVISIBLE (-1700 4400);
FORCEADD TAP..6
R 2
(-1700 4050);
FORCEPROP 3 LASTPIN (-1750 4050) SIG_NAME M_M_DQ<49>
J 0
(-1740 4060);
DISPLAY 0.659574 (-1740 4060);
PAINT MONO (-1740 4060);
DISPLAY INVISIBLE (-1740 4060);
FORCEPROP 1 LASTPIN (-1750 4050) BN 49
J 2
(-1700 4060);
DISPLAY 0.617021 (-1700 4060);
PAINT PINK (-1700 4060);
FORCEPROP 2 LAST CDS_LIB mstr_standard
J 2
(-1700 4050);
DISPLAY 0.787234 (-1700 4050);
PAINT MONO (-1700 4050);
DISPLAY INVISIBLE (-1700 4050);
FORCEPROP 1 LAST BODY_TYPE PLUMBING
J 2
(-1700 4000);
DISPLAY 1.234043 (-1700 4000);
PAINT GREEN (-1700 4000);
DISPLAY INVISIBLE (-1700 4000);
FORCEPROP 1 LAST HDL_TAP TRUE
J 2
(-2025 3925);
DISPLAY 1.234043 (-2025 3925);
PAINT GREEN (-2025 3925);
DISPLAY INVISIBLE (-2025 3925);
FORCEPROP 1 LAST PATH I45
J 2
(-1700 4050);
DISPLAY 0.936170 (-1700 4050);
PAINT GREEN (-1700 4050);
DISPLAY INVISIBLE (-1700 4050);
FORCEADD TAP..6
R 2
(-1700 4250);
FORCEPROP 3 LASTPIN (-1750 4250) SIG_NAME M_M_DQ<53>
J 0
(-1740 4260);
DISPLAY 0.659574 (-1740 4260);
PAINT MONO (-1740 4260);
DISPLAY INVISIBLE (-1740 4260);
FORCEPROP 1 LASTPIN (-1750 4250) BN 53
J 2
(-1700 4260);
DISPLAY 0.617021 (-1700 4260);
PAINT PINK (-1700 4260);
FORCEPROP 2 LAST CDS_LIB mstr_standard
J 2
(-1700 4250);
DISPLAY 0.787234 (-1700 4250);
PAINT MONO (-1700 4250);
DISPLAY INVISIBLE (-1700 4250);
FORCEPROP 1 LAST BODY_TYPE PLUMBING
J 2
(-1700 4200);
DISPLAY 1.234043 (-1700 4200);
PAINT GREEN (-1700 4200);
DISPLAY INVISIBLE (-1700 4200);
FORCEPROP 1 LAST HDL_TAP TRUE
J 2
(-2025 4125);
DISPLAY 1.234043 (-2025 4125);
PAINT GREEN (-2025 4125);
DISPLAY INVISIBLE (-2025 4125);
FORCEPROP 1 LAST PATH I46
J 2
(-1700 4250);
DISPLAY 0.936170 (-1700 4250);
PAINT GREEN (-1700 4250);
DISPLAY INVISIBLE (-1700 4250);
FORCEADD TAP..6
R 2
(-1700 4200);
FORCEPROP 3 LASTPIN (-1750 4200) SIG_NAME M_M_DQ<52>
J 0
(-1740 4210);
DISPLAY 0.659574 (-1740 4210);
PAINT MONO (-1740 4210);
DISPLAY INVISIBLE (-1740 4210);
FORCEPROP 1 LASTPIN (-1750 4200) BN 52
J 2
(-1700 4210);
DISPLAY 0.617021 (-1700 4210);
PAINT PINK (-1700 4210);
FORCEPROP 2 LAST CDS_LIB mstr_standard
J 2
(-1700 4200);
DISPLAY 0.787234 (-1700 4200);
PAINT MONO (-1700 4200);
DISPLAY INVISIBLE (-1700 4200);
FORCEPROP 1 LAST BODY_TYPE PLUMBING
J 2
(-1700 4150);
DISPLAY 1.234043 (-1700 4150);
PAINT GREEN (-1700 4150);
DISPLAY INVISIBLE (-1700 4150);
FORCEPROP 1 LAST HDL_TAP TRUE
J 2
(-2025 4075);
DISPLAY 1.234043 (-2025 4075);
PAINT GREEN (-2025 4075);
DISPLAY INVISIBLE (-2025 4075);
FORCEPROP 1 LAST PATH I47
J 2
(-1700 4200);
DISPLAY 0.936170 (-1700 4200);
PAINT GREEN (-1700 4200);
DISPLAY INVISIBLE (-1700 4200);
FORCEADD TAP..6
R 2
(-1700 4100);
FORCEPROP 3 LASTPIN (-1750 4100) SIG_NAME M_M_DQ<50>
J 0
(-1740 4110);
DISPLAY 0.659574 (-1740 4110);
PAINT MONO (-1740 4110);
DISPLAY INVISIBLE (-1740 4110);
FORCEPROP 1 LASTPIN (-1750 4100) BN 50
J 2
(-1700 4110);
DISPLAY 0.617021 (-1700 4110);
PAINT PINK (-1700 4110);
FORCEPROP 2 LAST CDS_LIB mstr_standard
J 2
(-1700 4100);
DISPLAY 0.787234 (-1700 4100);
PAINT MONO (-1700 4100);
DISPLAY INVISIBLE (-1700 4100);
FORCEPROP 1 LAST BODY_TYPE PLUMBING
J 2
(-1700 4050);
DISPLAY 1.234043 (-1700 4050);
PAINT GREEN (-1700 4050);
DISPLAY INVISIBLE (-1700 4050);
FORCEPROP 1 LAST HDL_TAP TRUE
J 2
(-2025 3975);
DISPLAY 1.234043 (-2025 3975);
PAINT GREEN (-2025 3975);
DISPLAY INVISIBLE (-2025 3975);
FORCEPROP 1 LAST PATH I48
J 2
(-1700 4100);
DISPLAY 0.936170 (-1700 4100);
PAINT GREEN (-1700 4100);
DISPLAY INVISIBLE (-1700 4100);
FORCEADD TAP..6
R 2
(-1700 4150);
FORCEPROP 3 LASTPIN (-1750 4150) SIG_NAME M_M_DQ<51>
J 0
(-1740 4160);
DISPLAY 0.659574 (-1740 4160);
PAINT MONO (-1740 4160);
DISPLAY INVISIBLE (-1740 4160);
FORCEPROP 1 LASTPIN (-1750 4150) BN 51
J 2
(-1700 4160);
DISPLAY 0.617021 (-1700 4160);
PAINT PINK (-1700 4160);
FORCEPROP 2 LAST CDS_LIB mstr_standard
J 2
(-1700 4150);
DISPLAY 0.787234 (-1700 4150);
PAINT MONO (-1700 4150);
DISPLAY INVISIBLE (-1700 4150);
FORCEPROP 1 LAST BODY_TYPE PLUMBING
J 2
(-1700 4100);
DISPLAY 1.234043 (-1700 4100);
PAINT GREEN (-1700 4100);
DISPLAY INVISIBLE (-1700 4100);
FORCEPROP 1 LAST HDL_TAP TRUE
J 2
(-2025 4025);
DISPLAY 1.234043 (-2025 4025);
PAINT GREEN (-2025 4025);
DISPLAY INVISIBLE (-2025 4025);
FORCEPROP 1 LAST PATH I49
J 2
(-1700 4150);
DISPLAY 0.936170 (-1700 4150);
PAINT GREEN (-1700 4150);
DISPLAY INVISIBLE (-1700 4150);
FORCEADD TAP..6
R 2
(900 4900);
FORCEPROP 3 LASTPIN (850 4900) SIG_NAME M_M_DQS_DN<15>
J 0
(860 4910);
DISPLAY 0.659574 (860 4910);
PAINT MONO (860 4910);
DISPLAY INVISIBLE (860 4910);
FORCEPROP 1 LASTPIN (850 4900) BN 15
J 2
(900 4910);
DISPLAY 0.617021 (900 4910);
PAINT PINK (900 4910);
FORCEPROP 2 LAST CDS_LIB mstr_standard
J 0
(900 4900);
DISPLAY 0.787234 (900 4900);
PAINT MONO (900 4900);
DISPLAY INVISIBLE (900 4900);
FORCEPROP 1 LAST BODY_TYPE PLUMBING
J 2
(900 4850);
DISPLAY 1.234043 (900 4850);
PAINT GREEN (900 4850);
DISPLAY INVISIBLE (900 4850);
FORCEPROP 1 LAST HDL_TAP TRUE
J 2
(575 4775);
DISPLAY 1.234043 (575 4775);
PAINT GREEN (575 4775);
DISPLAY INVISIBLE (575 4775);
FORCEPROP 1 LAST PATH I5
J 2
(900 4900);
DISPLAY 0.936170 (900 4900);
PAINT GREEN (900 4900);
DISPLAY INVISIBLE (900 4900);
FORCEADD TAP..6
R 2
(-1700 3950);
FORCEPROP 3 LASTPIN (-1750 3950) SIG_NAME M_M_DQ<47>
J 0
(-1740 3960);
DISPLAY 0.659574 (-1740 3960);
PAINT MONO (-1740 3960);
DISPLAY INVISIBLE (-1740 3960);
FORCEPROP 1 LASTPIN (-1750 3950) BN 47
J 2
(-1700 3960);
DISPLAY 0.617021 (-1700 3960);
PAINT PINK (-1700 3960);
FORCEPROP 2 LAST CDS_LIB mstr_standard
J 2
(-1700 3950);
DISPLAY 0.787234 (-1700 3950);
PAINT MONO (-1700 3950);
DISPLAY INVISIBLE (-1700 3950);
FORCEPROP 1 LAST BODY_TYPE PLUMBING
J 2
(-1700 3900);
DISPLAY 1.234043 (-1700 3900);
PAINT GREEN (-1700 3900);
DISPLAY INVISIBLE (-1700 3900);
FORCEPROP 1 LAST HDL_TAP TRUE
J 2
(-2025 3825);
DISPLAY 1.234043 (-2025 3825);
PAINT GREEN (-2025 3825);
DISPLAY INVISIBLE (-2025 3825);
FORCEPROP 1 LAST PATH I50
J 2
(-1700 3950);
DISPLAY 0.936170 (-1700 3950);
PAINT GREEN (-1700 3950);
DISPLAY INVISIBLE (-1700 3950);
FORCEADD TAP..6
R 2
(-1700 4000);
FORCEPROP 3 LASTPIN (-1750 4000) SIG_NAME M_M_DQ<48>
J 0
(-1740 4010);
DISPLAY 0.659574 (-1740 4010);
PAINT MONO (-1740 4010);
DISPLAY INVISIBLE (-1740 4010);
FORCEPROP 1 LASTPIN (-1750 4000) BN 48
J 2
(-1700 4010);
DISPLAY 0.617021 (-1700 4010);
PAINT PINK (-1700 4010);
FORCEPROP 2 LAST CDS_LIB mstr_standard
J 2
(-1700 4000);
DISPLAY 0.787234 (-1700 4000);
PAINT MONO (-1700 4000);
DISPLAY INVISIBLE (-1700 4000);
FORCEPROP 1 LAST BODY_TYPE PLUMBING
J 2
(-1700 3950);
DISPLAY 1.234043 (-1700 3950);
PAINT GREEN (-1700 3950);
DISPLAY INVISIBLE (-1700 3950);
FORCEPROP 1 LAST HDL_TAP TRUE
J 2
(-2025 3875);
DISPLAY 1.234043 (-2025 3875);
PAINT GREEN (-2025 3875);
DISPLAY INVISIBLE (-2025 3875);
FORCEPROP 1 LAST PATH I51
J 2
(-1700 4000);
DISPLAY 0.936170 (-1700 4000);
PAINT GREEN (-1700 4000);
DISPLAY INVISIBLE (-1700 4000);
FORCEADD TAP..6
R 2
(-1700 3900);
FORCEPROP 3 LASTPIN (-1750 3900) SIG_NAME M_M_DQ<46>
J 0
(-1740 3910);
DISPLAY 0.659574 (-1740 3910);
PAINT MONO (-1740 3910);
DISPLAY INVISIBLE (-1740 3910);
FORCEPROP 1 LASTPIN (-1750 3900) BN 46
J 2
(-1700 3910);
DISPLAY 0.617021 (-1700 3910);
PAINT PINK (-1700 3910);
FORCEPROP 2 LAST CDS_LIB mstr_standard
J 2
(-1700 3900);
DISPLAY 0.787234 (-1700 3900);
PAINT MONO (-1700 3900);
DISPLAY INVISIBLE (-1700 3900);
FORCEPROP 1 LAST BODY_TYPE PLUMBING
J 2
(-1700 3850);
DISPLAY 1.234043 (-1700 3850);
PAINT GREEN (-1700 3850);
DISPLAY INVISIBLE (-1700 3850);
FORCEPROP 1 LAST HDL_TAP TRUE
J 2
(-2025 3775);
DISPLAY 1.234043 (-2025 3775);
PAINT GREEN (-2025 3775);
DISPLAY INVISIBLE (-2025 3775);
FORCEPROP 1 LAST PATH I52
J 2
(-1700 3900);
DISPLAY 0.936170 (-1700 3900);
PAINT GREEN (-1700 3900);
DISPLAY INVISIBLE (-1700 3900);
FORCEADD TAP..6
R 2
(-1700 3800);
FORCEPROP 3 LASTPIN (-1750 3800) SIG_NAME M_M_DQ<44>
J 0
(-1740 3810);
DISPLAY 0.659574 (-1740 3810);
PAINT MONO (-1740 3810);
DISPLAY INVISIBLE (-1740 3810);
FORCEPROP 1 LASTPIN (-1750 3800) BN 44
J 2
(-1700 3810);
DISPLAY 0.617021 (-1700 3810);
PAINT PINK (-1700 3810);
FORCEPROP 2 LAST CDS_LIB mstr_standard
J 2
(-1700 3800);
DISPLAY 0.787234 (-1700 3800);
PAINT MONO (-1700 3800);
DISPLAY INVISIBLE (-1700 3800);
FORCEPROP 1 LAST BODY_TYPE PLUMBING
J 2
(-1700 3750);
DISPLAY 1.234043 (-1700 3750);
PAINT GREEN (-1700 3750);
DISPLAY INVISIBLE (-1700 3750);
FORCEPROP 1 LAST HDL_TAP TRUE
J 2
(-2025 3675);
DISPLAY 1.234043 (-2025 3675);
PAINT GREEN (-2025 3675);
DISPLAY INVISIBLE (-2025 3675);
FORCEPROP 1 LAST PATH I53
J 2
(-1700 3800);
DISPLAY 0.936170 (-1700 3800);
PAINT GREEN (-1700 3800);
DISPLAY INVISIBLE (-1700 3800);
FORCEADD TAP..6
R 2
(-1700 3850);
FORCEPROP 3 LASTPIN (-1750 3850) SIG_NAME M_M_DQ<45>
J 0
(-1740 3860);
DISPLAY 0.659574 (-1740 3860);
PAINT MONO (-1740 3860);
DISPLAY INVISIBLE (-1740 3860);
FORCEPROP 1 LASTPIN (-1750 3850) BN 45
J 2
(-1700 3860);
DISPLAY 0.617021 (-1700 3860);
PAINT PINK (-1700 3860);
FORCEPROP 2 LAST CDS_LIB mstr_standard
J 2
(-1700 3850);
DISPLAY 0.787234 (-1700 3850);
PAINT MONO (-1700 3850);
DISPLAY INVISIBLE (-1700 3850);
FORCEPROP 1 LAST BODY_TYPE PLUMBING
J 2
(-1700 3800);
DISPLAY 1.234043 (-1700 3800);
PAINT GREEN (-1700 3800);
DISPLAY INVISIBLE (-1700 3800);
FORCEPROP 1 LAST HDL_TAP TRUE
J 2
(-2025 3725);
DISPLAY 1.234043 (-2025 3725);
PAINT GREEN (-2025 3725);
DISPLAY INVISIBLE (-2025 3725);
FORCEPROP 1 LAST PATH I54
J 2
(-1700 3850);
DISPLAY 0.936170 (-1700 3850);
PAINT GREEN (-1700 3850);
DISPLAY INVISIBLE (-1700 3850);
FORCEADD TAP..6
R 2
(700 4250);
FORCEPROP 3 LASTPIN (650 4250) SIG_NAME M_M_DQS_DP<8>
J 0
(660 4260);
DISPLAY 0.659574 (660 4260);
PAINT MONO (660 4260);
DISPLAY INVISIBLE (660 4260);
FORCEPROP 1 LASTPIN (650 4250) BN 8
J 2
(700 4260);
DISPLAY 0.617021 (700 4260);
PAINT PINK (700 4260);
FORCEPROP 2 LAST CDS_LIB mstr_standard
J 0
(700 4250);
DISPLAY 0.787234 (700 4250);
PAINT MONO (700 4250);
DISPLAY INVISIBLE (700 4250);
FORCEPROP 1 LAST BODY_TYPE PLUMBING
J 2
(700 4200);
DISPLAY 1.234043 (700 4200);
PAINT GREEN (700 4200);
DISPLAY INVISIBLE (700 4200);
FORCEPROP 1 LAST HDL_TAP TRUE
J 2
(375 4125);
DISPLAY 1.234043 (375 4125);
PAINT GREEN (375 4125);
DISPLAY INVISIBLE (375 4125);
FORCEPROP 1 LAST PATH I55
J 2
(700 4250);
DISPLAY 0.936170 (700 4250);
PAINT GREEN (700 4250);
DISPLAY INVISIBLE (700 4250);
FORCEADD TAP..6
R 2
(700 4150);
FORCEPROP 3 LASTPIN (650 4150) SIG_NAME M_M_DQS_DP<7>
J 0
(660 4160);
DISPLAY 0.659574 (660 4160);
PAINT MONO (660 4160);
DISPLAY INVISIBLE (660 4160);
FORCEPROP 1 LASTPIN (650 4150) BN 7
J 2
(700 4160);
DISPLAY 0.617021 (700 4160);
PAINT PINK (700 4160);
FORCEPROP 2 LAST CDS_LIB mstr_standard
J 0
(700 4150);
DISPLAY 0.787234 (700 4150);
PAINT MONO (700 4150);
DISPLAY INVISIBLE (700 4150);
FORCEPROP 1 LAST BODY_TYPE PLUMBING
J 2
(700 4100);
DISPLAY 1.234043 (700 4100);
PAINT GREEN (700 4100);
DISPLAY INVISIBLE (700 4100);
FORCEPROP 1 LAST HDL_TAP TRUE
J 2
(375 4025);
DISPLAY 1.234043 (375 4025);
PAINT GREEN (375 4025);
DISPLAY INVISIBLE (375 4025);
FORCEPROP 1 LAST PATH I56
J 2
(700 4150);
DISPLAY 0.936170 (700 4150);
PAINT GREEN (700 4150);
DISPLAY INVISIBLE (700 4150);
FORCEADD TAP..6
R 2
(700 4050);
FORCEPROP 3 LASTPIN (650 4050) SIG_NAME M_M_DQS_DP<6>
J 0
(660 4060);
DISPLAY 0.659574 (660 4060);
PAINT MONO (660 4060);
DISPLAY INVISIBLE (660 4060);
FORCEPROP 1 LASTPIN (650 4050) BN 6
J 2
(700 4060);
DISPLAY 0.617021 (700 4060);
PAINT PINK (700 4060);
FORCEPROP 2 LAST CDS_LIB mstr_standard
J 0
(700 4050);
DISPLAY 0.787234 (700 4050);
PAINT MONO (700 4050);
DISPLAY INVISIBLE (700 4050);
FORCEPROP 1 LAST BODY_TYPE PLUMBING
J 2
(700 4000);
DISPLAY 1.234043 (700 4000);
PAINT GREEN (700 4000);
DISPLAY INVISIBLE (700 4000);
FORCEPROP 1 LAST HDL_TAP TRUE
J 2
(375 3925);
DISPLAY 1.234043 (375 3925);
PAINT GREEN (375 3925);
DISPLAY INVISIBLE (375 3925);
FORCEPROP 1 LAST PATH I57
J 2
(700 4050);
DISPLAY 0.936170 (700 4050);
PAINT GREEN (700 4050);
DISPLAY INVISIBLE (700 4050);
FORCEADD TAP..6
R 2
(700 4350);
FORCEPROP 3 LASTPIN (650 4350) SIG_NAME M_M_DQS_DP<9>
J 0
(660 4360);
DISPLAY 0.659574 (660 4360);
PAINT MONO (660 4360);
DISPLAY INVISIBLE (660 4360);
FORCEPROP 1 LASTPIN (650 4350) BN 9
J 2
(700 4360);
DISPLAY 0.617021 (700 4360);
PAINT PINK (700 4360);
FORCEPROP 2 LAST CDS_LIB mstr_standard
J 0
(700 4350);
DISPLAY 0.787234 (700 4350);
PAINT MONO (700 4350);
DISPLAY INVISIBLE (700 4350);
FORCEPROP 1 LAST BODY_TYPE PLUMBING
J 2
(700 4300);
DISPLAY 1.234043 (700 4300);
PAINT GREEN (700 4300);
DISPLAY INVISIBLE (700 4300);
FORCEPROP 1 LAST HDL_TAP TRUE
J 2
(375 4225);
DISPLAY 1.234043 (375 4225);
PAINT GREEN (375 4225);
DISPLAY INVISIBLE (375 4225);
FORCEPROP 1 LAST PATH I58
J 2
(700 4350);
DISPLAY 0.936170 (700 4350);
PAINT GREEN (700 4350);
DISPLAY INVISIBLE (700 4350);
FORCEADD TAP..6
R 2
(700 4450);
FORCEPROP 3 LASTPIN (650 4450) SIG_NAME M_M_DQS_DP<10>
J 0
(660 4460);
DISPLAY 0.659574 (660 4460);
PAINT MONO (660 4460);
DISPLAY INVISIBLE (660 4460);
FORCEPROP 1 LASTPIN (650 4450) BN 10
J 2
(700 4460);
DISPLAY 0.617021 (700 4460);
PAINT PINK (700 4460);
FORCEPROP 2 LAST CDS_LIB mstr_standard
J 0
(700 4450);
DISPLAY 0.787234 (700 4450);
PAINT MONO (700 4450);
DISPLAY INVISIBLE (700 4450);
FORCEPROP 1 LAST BODY_TYPE PLUMBING
J 2
(700 4400);
DISPLAY 1.234043 (700 4400);
PAINT GREEN (700 4400);
DISPLAY INVISIBLE (700 4400);
FORCEPROP 1 LAST HDL_TAP TRUE
J 2
(375 4325);
DISPLAY 1.234043 (375 4325);
PAINT GREEN (375 4325);
DISPLAY INVISIBLE (375 4325);
FORCEPROP 1 LAST PATH I59
J 2
(700 4450);
DISPLAY 0.936170 (700 4450);
PAINT GREEN (700 4450);
DISPLAY INVISIBLE (700 4450);
FORCEADD TAP..6
R 2
(900 4800);
FORCEPROP 3 LASTPIN (850 4800) SIG_NAME M_M_DQS_DN<14>
J 0
(860 4810);
DISPLAY 0.659574 (860 4810);
PAINT MONO (860 4810);
DISPLAY INVISIBLE (860 4810);
FORCEPROP 1 LASTPIN (850 4800) BN 14
J 2
(900 4810);
DISPLAY 0.617021 (900 4810);
PAINT PINK (900 4810);
FORCEPROP 2 LAST CDS_LIB mstr_standard
J 0
(900 4800);
DISPLAY 0.787234 (900 4800);
PAINT MONO (900 4800);
DISPLAY INVISIBLE (900 4800);
FORCEPROP 1 LAST BODY_TYPE PLUMBING
J 2
(900 4750);
DISPLAY 1.234043 (900 4750);
PAINT GREEN (900 4750);
DISPLAY INVISIBLE (900 4750);
FORCEPROP 1 LAST HDL_TAP TRUE
J 2
(575 4675);
DISPLAY 1.234043 (575 4675);
PAINT GREEN (575 4675);
DISPLAY INVISIBLE (575 4675);
FORCEPROP 1 LAST PATH I6
J 2
(900 4800);
DISPLAY 0.936170 (900 4800);
PAINT GREEN (900 4800);
DISPLAY INVISIBLE (900 4800);
FORCEADD TAP..6
R 2
(700 3750);
FORCEPROP 3 LASTPIN (650 3750) SIG_NAME M_M_DQS_DP<3>
J 0
(660 3760);
DISPLAY 0.659574 (660 3760);
PAINT MONO (660 3760);
DISPLAY INVISIBLE (660 3760);
FORCEPROP 1 LASTPIN (650 3750) BN 3
J 2
(700 3760);
DISPLAY 0.617021 (700 3760);
PAINT PINK (700 3760);
FORCEPROP 2 LAST CDS_LIB mstr_standard
J 0
(700 3750);
DISPLAY 0.787234 (700 3750);
PAINT MONO (700 3750);
DISPLAY INVISIBLE (700 3750);
FORCEPROP 1 LAST BODY_TYPE PLUMBING
J 2
(700 3700);
DISPLAY 1.234043 (700 3700);
PAINT GREEN (700 3700);
DISPLAY INVISIBLE (700 3700);
FORCEPROP 1 LAST HDL_TAP TRUE
J 2
(375 3625);
DISPLAY 1.234043 (375 3625);
PAINT GREEN (375 3625);
DISPLAY INVISIBLE (375 3625);
FORCEPROP 1 LAST PATH I60
J 2
(700 3750);
DISPLAY 0.936170 (700 3750);
PAINT GREEN (700 3750);
DISPLAY INVISIBLE (700 3750);
FORCEADD TAP..6
R 2
(700 3550);
FORCEPROP 3 LASTPIN (650 3550) SIG_NAME M_M_DQS_DP<1>
J 0
(660 3560);
DISPLAY 0.659574 (660 3560);
PAINT MONO (660 3560);
DISPLAY INVISIBLE (660 3560);
FORCEPROP 1 LASTPIN (650 3550) BN 1
J 2
(700 3560);
DISPLAY 0.617021 (700 3560);
PAINT PINK (700 3560);
FORCEPROP 2 LAST CDS_LIB mstr_standard
J 0
(700 3550);
DISPLAY 0.787234 (700 3550);
PAINT MONO (700 3550);
DISPLAY INVISIBLE (700 3550);
FORCEPROP 1 LAST BODY_TYPE PLUMBING
J 2
(700 3500);
DISPLAY 1.234043 (700 3500);
PAINT GREEN (700 3500);
DISPLAY INVISIBLE (700 3500);
FORCEPROP 1 LAST HDL_TAP TRUE
J 2
(375 3425);
DISPLAY 1.234043 (375 3425);
PAINT GREEN (375 3425);
DISPLAY INVISIBLE (375 3425);
FORCEPROP 1 LAST PATH I61
J 2
(700 3550);
DISPLAY 0.936170 (700 3550);
PAINT GREEN (700 3550);
DISPLAY INVISIBLE (700 3550);
FORCEADD TAP..6
R 2
(700 3650);
FORCEPROP 3 LASTPIN (650 3650) SIG_NAME M_M_DQS_DP<2>
J 0
(660 3660);
DISPLAY 0.659574 (660 3660);
PAINT MONO (660 3660);
DISPLAY INVISIBLE (660 3660);
FORCEPROP 1 LASTPIN (650 3650) BN 2
J 2
(700 3660);
DISPLAY 0.617021 (700 3660);
PAINT PINK (700 3660);
FORCEPROP 2 LAST CDS_LIB mstr_standard
J 0
(700 3650);
DISPLAY 0.787234 (700 3650);
PAINT MONO (700 3650);
DISPLAY INVISIBLE (700 3650);
FORCEPROP 1 LAST BODY_TYPE PLUMBING
J 2
(700 3600);
DISPLAY 1.234043 (700 3600);
PAINT GREEN (700 3600);
DISPLAY INVISIBLE (700 3600);
FORCEPROP 1 LAST HDL_TAP TRUE
J 2
(375 3525);
DISPLAY 1.234043 (375 3525);
PAINT GREEN (375 3525);
DISPLAY INVISIBLE (375 3525);
FORCEPROP 1 LAST PATH I62
J 2
(700 3650);
DISPLAY 0.936170 (700 3650);
PAINT GREEN (700 3650);
DISPLAY INVISIBLE (700 3650);
FORCEADD TAP..6
R 2
(700 3950);
FORCEPROP 3 LASTPIN (650 3950) SIG_NAME M_M_DQS_DP<5>
J 0
(660 3960);
DISPLAY 0.659574 (660 3960);
PAINT MONO (660 3960);
DISPLAY INVISIBLE (660 3960);
FORCEPROP 1 LASTPIN (650 3950) BN 5
J 2
(700 3960);
DISPLAY 0.617021 (700 3960);
PAINT PINK (700 3960);
FORCEPROP 2 LAST CDS_LIB mstr_standard
J 0
(700 3950);
DISPLAY 0.787234 (700 3950);
PAINT MONO (700 3950);
DISPLAY INVISIBLE (700 3950);
FORCEPROP 1 LAST BODY_TYPE PLUMBING
J 2
(700 3900);
DISPLAY 1.234043 (700 3900);
PAINT GREEN (700 3900);
DISPLAY INVISIBLE (700 3900);
FORCEPROP 1 LAST HDL_TAP TRUE
J 2
(375 3825);
DISPLAY 1.234043 (375 3825);
PAINT GREEN (375 3825);
DISPLAY INVISIBLE (375 3825);
FORCEPROP 1 LAST PATH I63
J 2
(700 3950);
DISPLAY 0.936170 (700 3950);
PAINT GREEN (700 3950);
DISPLAY INVISIBLE (700 3950);
FORCEADD TAP..6
R 2
(700 3850);
FORCEPROP 3 LASTPIN (650 3850) SIG_NAME M_M_DQS_DP<4>
J 0
(660 3860);
DISPLAY 0.659574 (660 3860);
PAINT MONO (660 3860);
DISPLAY INVISIBLE (660 3860);
FORCEPROP 1 LASTPIN (650 3850) BN 4
J 2
(700 3860);
DISPLAY 0.617021 (700 3860);
PAINT PINK (700 3860);
FORCEPROP 2 LAST CDS_LIB mstr_standard
J 0
(700 3850);
DISPLAY 0.787234 (700 3850);
PAINT MONO (700 3850);
DISPLAY INVISIBLE (700 3850);
FORCEPROP 1 LAST BODY_TYPE PLUMBING
J 2
(700 3800);
DISPLAY 1.234043 (700 3800);
PAINT GREEN (700 3800);
DISPLAY INVISIBLE (700 3800);
FORCEPROP 1 LAST HDL_TAP TRUE
J 2
(375 3725);
DISPLAY 1.234043 (375 3725);
PAINT GREEN (375 3725);
DISPLAY INVISIBLE (375 3725);
FORCEPROP 1 LAST PATH I64
J 2
(700 3850);
DISPLAY 0.936170 (700 3850);
PAINT GREEN (700 3850);
DISPLAY INVISIBLE (700 3850);
FORCEADD TAP..6
R 2
(700 3450);
FORCEPROP 3 LASTPIN (650 3450) SIG_NAME M_M_DQS_DP<0>
J 0
(660 3460);
DISPLAY 0.659574 (660 3460);
PAINT MONO (660 3460);
DISPLAY INVISIBLE (660 3460);
FORCEPROP 1 LASTPIN (650 3450) BN 0
J 2
(700 3460);
DISPLAY 0.617021 (700 3460);
PAINT PINK (700 3460);
FORCEPROP 2 LAST CDS_LIB mstr_standard
J 0
(700 3450);
DISPLAY 0.787234 (700 3450);
PAINT MONO (700 3450);
DISPLAY INVISIBLE (700 3450);
FORCEPROP 1 LAST BODY_TYPE PLUMBING
J 2
(700 3400);
DISPLAY 1.234043 (700 3400);
PAINT GREEN (700 3400);
DISPLAY INVISIBLE (700 3400);
FORCEPROP 1 LAST HDL_TAP TRUE
J 2
(375 3325);
DISPLAY 1.234043 (375 3325);
PAINT GREEN (375 3325);
DISPLAY INVISIBLE (375 3325);
FORCEPROP 1 LAST PATH I65
J 2
(700 3450);
DISPLAY 0.936170 (700 3450);
PAINT GREEN (700 3450);
DISPLAY INVISIBLE (700 3450);
FORCEADD TAP..6
R 2
(-1700 3750);
FORCEPROP 3 LASTPIN (-1750 3750) SIG_NAME M_M_DQ<43>
J 0
(-1740 3760);
DISPLAY 0.659574 (-1740 3760);
PAINT MONO (-1740 3760);
DISPLAY INVISIBLE (-1740 3760);
FORCEPROP 1 LASTPIN (-1750 3750) BN 43
J 2
(-1700 3760);
DISPLAY 0.617021 (-1700 3760);
PAINT PINK (-1700 3760);
FORCEPROP 2 LAST CDS_LIB mstr_standard
J 2
(-1700 3750);
DISPLAY 0.787234 (-1700 3750);
PAINT MONO (-1700 3750);
DISPLAY INVISIBLE (-1700 3750);
FORCEPROP 1 LAST BODY_TYPE PLUMBING
J 2
(-1700 3700);
DISPLAY 1.234043 (-1700 3700);
PAINT GREEN (-1700 3700);
DISPLAY INVISIBLE (-1700 3700);
FORCEPROP 1 LAST HDL_TAP TRUE
J 2
(-2025 3625);
DISPLAY 1.234043 (-2025 3625);
PAINT GREEN (-2025 3625);
DISPLAY INVISIBLE (-2025 3625);
FORCEPROP 1 LAST PATH I66
J 2
(-1700 3750);
DISPLAY 0.936170 (-1700 3750);
PAINT GREEN (-1700 3750);
DISPLAY INVISIBLE (-1700 3750);
FORCEADD TAP..6
R 2
(-1700 3700);
FORCEPROP 3 LASTPIN (-1750 3700) SIG_NAME M_M_DQ<42>
J 0
(-1740 3710);
DISPLAY 0.659574 (-1740 3710);
PAINT MONO (-1740 3710);
DISPLAY INVISIBLE (-1740 3710);
FORCEPROP 1 LASTPIN (-1750 3700) BN 42
J 2
(-1700 3710);
DISPLAY 0.617021 (-1700 3710);
PAINT PINK (-1700 3710);
FORCEPROP 2 LAST CDS_LIB mstr_standard
J 2
(-1700 3700);
DISPLAY 0.787234 (-1700 3700);
PAINT MONO (-1700 3700);
DISPLAY INVISIBLE (-1700 3700);
FORCEPROP 1 LAST BODY_TYPE PLUMBING
J 2
(-1700 3650);
DISPLAY 1.234043 (-1700 3650);
PAINT GREEN (-1700 3650);
DISPLAY INVISIBLE (-1700 3650);
FORCEPROP 1 LAST HDL_TAP TRUE
J 2
(-2025 3575);
DISPLAY 1.234043 (-2025 3575);
PAINT GREEN (-2025 3575);
DISPLAY INVISIBLE (-2025 3575);
FORCEPROP 1 LAST PATH I67
J 2
(-1700 3700);
DISPLAY 0.936170 (-1700 3700);
PAINT GREEN (-1700 3700);
DISPLAY INVISIBLE (-1700 3700);
FORCEADD TAP..6
R 2
(-1700 3600);
FORCEPROP 3 LASTPIN (-1750 3600) SIG_NAME M_M_DQ<40>
J 0
(-1740 3610);
DISPLAY 0.659574 (-1740 3610);
PAINT MONO (-1740 3610);
DISPLAY INVISIBLE (-1740 3610);
FORCEPROP 1 LASTPIN (-1750 3600) BN 40
J 2
(-1700 3610);
DISPLAY 0.617021 (-1700 3610);
PAINT PINK (-1700 3610);
FORCEPROP 2 LAST CDS_LIB mstr_standard
J 2
(-1700 3600);
DISPLAY 0.787234 (-1700 3600);
PAINT MONO (-1700 3600);
DISPLAY INVISIBLE (-1700 3600);
FORCEPROP 1 LAST BODY_TYPE PLUMBING
J 2
(-1700 3550);
DISPLAY 1.234043 (-1700 3550);
PAINT GREEN (-1700 3550);
DISPLAY INVISIBLE (-1700 3550);
FORCEPROP 1 LAST HDL_TAP TRUE
J 2
(-2025 3475);
DISPLAY 1.234043 (-2025 3475);
PAINT GREEN (-2025 3475);
DISPLAY INVISIBLE (-2025 3475);
FORCEPROP 1 LAST PATH I68
J 2
(-1700 3600);
DISPLAY 0.936170 (-1700 3600);
PAINT GREEN (-1700 3600);
DISPLAY INVISIBLE (-1700 3600);
FORCEADD TAP..6
R 2
(-1700 3650);
FORCEPROP 3 LASTPIN (-1750 3650) SIG_NAME M_M_DQ<41>
J 0
(-1740 3660);
DISPLAY 0.659574 (-1740 3660);
PAINT MONO (-1740 3660);
DISPLAY INVISIBLE (-1740 3660);
FORCEPROP 1 LASTPIN (-1750 3650) BN 41
J 2
(-1700 3660);
DISPLAY 0.617021 (-1700 3660);
PAINT PINK (-1700 3660);
FORCEPROP 2 LAST CDS_LIB mstr_standard
J 2
(-1700 3650);
DISPLAY 0.787234 (-1700 3650);
PAINT MONO (-1700 3650);
DISPLAY INVISIBLE (-1700 3650);
FORCEPROP 1 LAST BODY_TYPE PLUMBING
J 2
(-1700 3600);
DISPLAY 1.234043 (-1700 3600);
PAINT GREEN (-1700 3600);
DISPLAY INVISIBLE (-1700 3600);
FORCEPROP 1 LAST HDL_TAP TRUE
J 2
(-2025 3525);
DISPLAY 1.234043 (-2025 3525);
PAINT GREEN (-2025 3525);
DISPLAY INVISIBLE (-2025 3525);
FORCEPROP 1 LAST PATH I69
J 2
(-1700 3650);
DISPLAY 0.936170 (-1700 3650);
PAINT GREEN (-1700 3650);
DISPLAY INVISIBLE (-1700 3650);
FORCEADD TAP..6
R 2
(900 4700);
FORCEPROP 3 LASTPIN (850 4700) SIG_NAME M_M_DQS_DN<13>
J 0
(860 4710);
DISPLAY 0.659574 (860 4710);
PAINT MONO (860 4710);
DISPLAY INVISIBLE (860 4710);
FORCEPROP 1 LASTPIN (850 4700) BN 13
J 2
(900 4710);
DISPLAY 0.617021 (900 4710);
PAINT PINK (900 4710);
FORCEPROP 2 LAST CDS_LIB mstr_standard
J 0
(900 4700);
DISPLAY 0.787234 (900 4700);
PAINT MONO (900 4700);
DISPLAY INVISIBLE (900 4700);
FORCEPROP 1 LAST BODY_TYPE PLUMBING
J 2
(900 4650);
DISPLAY 1.234043 (900 4650);
PAINT GREEN (900 4650);
DISPLAY INVISIBLE (900 4650);
FORCEPROP 1 LAST HDL_TAP TRUE
J 2
(575 4575);
DISPLAY 1.234043 (575 4575);
PAINT GREEN (575 4575);
DISPLAY INVISIBLE (575 4575);
FORCEPROP 1 LAST PATH I7
J 2
(900 4700);
DISPLAY 0.936170 (900 4700);
PAINT GREEN (900 4700);
DISPLAY INVISIBLE (900 4700);
FORCEADD TAP..6
R 2
(-1700 3550);
FORCEPROP 3 LASTPIN (-1750 3550) SIG_NAME M_M_DQ<39>
J 0
(-1740 3560);
DISPLAY 0.659574 (-1740 3560);
PAINT MONO (-1740 3560);
DISPLAY INVISIBLE (-1740 3560);
FORCEPROP 1 LASTPIN (-1750 3550) BN 39
J 2
(-1700 3560);
DISPLAY 0.617021 (-1700 3560);
PAINT PINK (-1700 3560);
FORCEPROP 2 LAST CDS_LIB mstr_standard
J 2
(-1700 3550);
DISPLAY 0.787234 (-1700 3550);
PAINT MONO (-1700 3550);
DISPLAY INVISIBLE (-1700 3550);
FORCEPROP 1 LAST BODY_TYPE PLUMBING
J 2
(-1700 3500);
DISPLAY 1.234043 (-1700 3500);
PAINT GREEN (-1700 3500);
DISPLAY INVISIBLE (-1700 3500);
FORCEPROP 1 LAST HDL_TAP TRUE
J 2
(-2025 3425);
DISPLAY 1.234043 (-2025 3425);
PAINT GREEN (-2025 3425);
DISPLAY INVISIBLE (-2025 3425);
FORCEPROP 1 LAST PATH I70
J 2
(-1700 3550);
DISPLAY 0.936170 (-1700 3550);
PAINT GREEN (-1700 3550);
DISPLAY INVISIBLE (-1700 3550);
FORCEADD TAP..6
R 2
(-1700 3500);
FORCEPROP 3 LASTPIN (-1750 3500) SIG_NAME M_M_DQ<38>
J 0
(-1740 3510);
DISPLAY 0.659574 (-1740 3510);
PAINT MONO (-1740 3510);
DISPLAY INVISIBLE (-1740 3510);
FORCEPROP 1 LASTPIN (-1750 3500) BN 38
J 2
(-1700 3510);
DISPLAY 0.617021 (-1700 3510);
PAINT PINK (-1700 3510);
FORCEPROP 2 LAST CDS_LIB mstr_standard
J 2
(-1700 3500);
DISPLAY 0.787234 (-1700 3500);
PAINT MONO (-1700 3500);
DISPLAY INVISIBLE (-1700 3500);
FORCEPROP 1 LAST BODY_TYPE PLUMBING
J 2
(-1700 3450);
DISPLAY 1.234043 (-1700 3450);
PAINT GREEN (-1700 3450);
DISPLAY INVISIBLE (-1700 3450);
FORCEPROP 1 LAST HDL_TAP TRUE
J 2
(-2025 3375);
DISPLAY 1.234043 (-2025 3375);
PAINT GREEN (-2025 3375);
DISPLAY INVISIBLE (-2025 3375);
FORCEPROP 1 LAST PATH I71
J 2
(-1700 3500);
DISPLAY 0.936170 (-1700 3500);
PAINT GREEN (-1700 3500);
DISPLAY INVISIBLE (-1700 3500);
FORCEADD TAP..6
R 2
(-1700 3450);
FORCEPROP 3 LASTPIN (-1750 3450) SIG_NAME M_M_DQ<37>
J 0
(-1740 3460);
DISPLAY 0.659574 (-1740 3460);
PAINT MONO (-1740 3460);
DISPLAY INVISIBLE (-1740 3460);
FORCEPROP 1 LASTPIN (-1750 3450) BN 37
J 2
(-1700 3460);
DISPLAY 0.617021 (-1700 3460);
PAINT PINK (-1700 3460);
FORCEPROP 2 LAST CDS_LIB mstr_standard
J 2
(-1700 3450);
DISPLAY 0.787234 (-1700 3450);
PAINT MONO (-1700 3450);
DISPLAY INVISIBLE (-1700 3450);
FORCEPROP 1 LAST BODY_TYPE PLUMBING
J 2
(-1700 3400);
DISPLAY 1.234043 (-1700 3400);
PAINT GREEN (-1700 3400);
DISPLAY INVISIBLE (-1700 3400);
FORCEPROP 1 LAST HDL_TAP TRUE
J 2
(-2025 3325);
DISPLAY 1.234043 (-2025 3325);
PAINT GREEN (-2025 3325);
DISPLAY INVISIBLE (-2025 3325);
FORCEPROP 1 LAST PATH I72
J 2
(-1700 3450);
DISPLAY 0.936170 (-1700 3450);
PAINT GREEN (-1700 3450);
DISPLAY INVISIBLE (-1700 3450);
FORCEADD TAP..6
R 2
(-1700 3400);
FORCEPROP 3 LASTPIN (-1750 3400) SIG_NAME M_M_DQ<36>
J 0
(-1740 3410);
DISPLAY 0.659574 (-1740 3410);
PAINT MONO (-1740 3410);
DISPLAY INVISIBLE (-1740 3410);
FORCEPROP 1 LASTPIN (-1750 3400) BN 36
J 2
(-1700 3410);
DISPLAY 0.617021 (-1700 3410);
PAINT PINK (-1700 3410);
FORCEPROP 2 LAST CDS_LIB mstr_standard
J 2
(-1700 3400);
DISPLAY 0.787234 (-1700 3400);
PAINT MONO (-1700 3400);
DISPLAY INVISIBLE (-1700 3400);
FORCEPROP 1 LAST BODY_TYPE PLUMBING
J 2
(-1700 3350);
DISPLAY 1.234043 (-1700 3350);
PAINT GREEN (-1700 3350);
DISPLAY INVISIBLE (-1700 3350);
FORCEPROP 1 LAST HDL_TAP TRUE
J 2
(-2025 3275);
DISPLAY 1.234043 (-2025 3275);
PAINT GREEN (-2025 3275);
DISPLAY INVISIBLE (-2025 3275);
FORCEPROP 1 LAST PATH I73
J 2
(-1700 3400);
DISPLAY 0.936170 (-1700 3400);
PAINT GREEN (-1700 3400);
DISPLAY INVISIBLE (-1700 3400);
FORCEADD TAP..6
R 2
(-1700 3350);
FORCEPROP 3 LASTPIN (-1750 3350) SIG_NAME M_M_DQ<35>
J 0
(-1740 3360);
DISPLAY 0.659574 (-1740 3360);
PAINT MONO (-1740 3360);
DISPLAY INVISIBLE (-1740 3360);
FORCEPROP 1 LASTPIN (-1750 3350) BN 35
J 2
(-1700 3360);
DISPLAY 0.617021 (-1700 3360);
PAINT PINK (-1700 3360);
FORCEPROP 2 LAST CDS_LIB mstr_standard
J 2
(-1700 3350);
DISPLAY 0.787234 (-1700 3350);
PAINT MONO (-1700 3350);
DISPLAY INVISIBLE (-1700 3350);
FORCEPROP 1 LAST BODY_TYPE PLUMBING
J 2
(-1700 3300);
DISPLAY 1.234043 (-1700 3300);
PAINT GREEN (-1700 3300);
DISPLAY INVISIBLE (-1700 3300);
FORCEPROP 1 LAST HDL_TAP TRUE
J 2
(-2025 3225);
DISPLAY 1.234043 (-2025 3225);
PAINT GREEN (-2025 3225);
DISPLAY INVISIBLE (-2025 3225);
FORCEPROP 1 LAST PATH I74
J 2
(-1700 3350);
DISPLAY 0.936170 (-1700 3350);
PAINT GREEN (-1700 3350);
DISPLAY INVISIBLE (-1700 3350);
FORCEADD TAP..6
R 2
(-1700 3300);
FORCEPROP 3 LASTPIN (-1750 3300) SIG_NAME M_M_DQ<34>
J 0
(-1740 3310);
DISPLAY 0.659574 (-1740 3310);
PAINT MONO (-1740 3310);
DISPLAY INVISIBLE (-1740 3310);
FORCEPROP 1 LASTPIN (-1750 3300) BN 34
J 2
(-1700 3310);
DISPLAY 0.617021 (-1700 3310);
PAINT PINK (-1700 3310);
FORCEPROP 2 LAST CDS_LIB mstr_standard
J 2
(-1700 3300);
DISPLAY 0.787234 (-1700 3300);
PAINT MONO (-1700 3300);
DISPLAY INVISIBLE (-1700 3300);
FORCEPROP 1 LAST BODY_TYPE PLUMBING
J 2
(-1700 3250);
DISPLAY 1.234043 (-1700 3250);
PAINT GREEN (-1700 3250);
DISPLAY INVISIBLE (-1700 3250);
FORCEPROP 1 LAST HDL_TAP TRUE
J 2
(-2025 3175);
DISPLAY 1.234043 (-2025 3175);
PAINT GREEN (-2025 3175);
DISPLAY INVISIBLE (-2025 3175);
FORCEPROP 1 LAST PATH I75
J 2
(-1700 3300);
DISPLAY 0.936170 (-1700 3300);
PAINT GREEN (-1700 3300);
DISPLAY INVISIBLE (-1700 3300);
FORCEADD TAP..6
R 2
(-1700 3250);
FORCEPROP 3 LASTPIN (-1750 3250) SIG_NAME M_M_DQ<33>
J 0
(-1740 3260);
DISPLAY 0.659574 (-1740 3260);
PAINT MONO (-1740 3260);
DISPLAY INVISIBLE (-1740 3260);
FORCEPROP 1 LASTPIN (-1750 3250) BN 33
J 2
(-1700 3260);
DISPLAY 0.617021 (-1700 3260);
PAINT PINK (-1700 3260);
FORCEPROP 2 LAST CDS_LIB mstr_standard
J 2
(-1700 3250);
DISPLAY 0.787234 (-1700 3250);
PAINT MONO (-1700 3250);
DISPLAY INVISIBLE (-1700 3250);
FORCEPROP 1 LAST BODY_TYPE PLUMBING
J 2
(-1700 3200);
DISPLAY 1.234043 (-1700 3200);
PAINT GREEN (-1700 3200);
DISPLAY INVISIBLE (-1700 3200);
FORCEPROP 1 LAST HDL_TAP TRUE
J 2
(-2025 3125);
DISPLAY 1.234043 (-2025 3125);
PAINT GREEN (-2025 3125);
DISPLAY INVISIBLE (-2025 3125);
FORCEPROP 1 LAST PATH I76
J 2
(-1700 3250);
DISPLAY 0.936170 (-1700 3250);
PAINT GREEN (-1700 3250);
DISPLAY INVISIBLE (-1700 3250);
FORCEADD TAP..6
R 2
(-1700 3200);
FORCEPROP 3 LASTPIN (-1750 3200) SIG_NAME M_M_DQ<32>
J 0
(-1740 3210);
DISPLAY 0.659574 (-1740 3210);
PAINT MONO (-1740 3210);
DISPLAY INVISIBLE (-1740 3210);
FORCEPROP 1 LASTPIN (-1750 3200) BN 32
J 2
(-1700 3210);
DISPLAY 0.617021 (-1700 3210);
PAINT PINK (-1700 3210);
FORCEPROP 2 LAST CDS_LIB mstr_standard
J 2
(-1700 3200);
DISPLAY 0.787234 (-1700 3200);
PAINT MONO (-1700 3200);
DISPLAY INVISIBLE (-1700 3200);
FORCEPROP 1 LAST BODY_TYPE PLUMBING
J 2
(-1700 3150);
DISPLAY 1.234043 (-1700 3150);
PAINT GREEN (-1700 3150);
DISPLAY INVISIBLE (-1700 3150);
FORCEPROP 1 LAST HDL_TAP TRUE
J 2
(-2025 3075);
DISPLAY 1.234043 (-2025 3075);
PAINT GREEN (-2025 3075);
DISPLAY INVISIBLE (-2025 3075);
FORCEPROP 1 LAST PATH I77
J 2
(-1700 3200);
DISPLAY 0.936170 (-1700 3200);
PAINT GREEN (-1700 3200);
DISPLAY INVISIBLE (-1700 3200);
FORCEADD TAP..6
R 2
(-1700 3050);
FORCEPROP 3 LASTPIN (-1750 3050) SIG_NAME M_M_DQ<29>
J 0
(-1740 3060);
DISPLAY 0.659574 (-1740 3060);
PAINT MONO (-1740 3060);
DISPLAY INVISIBLE (-1740 3060);
FORCEPROP 1 LASTPIN (-1750 3050) BN 29
J 2
(-1700 3060);
DISPLAY 0.617021 (-1700 3060);
PAINT PINK (-1700 3060);
FORCEPROP 2 LAST CDS_LIB mstr_standard
J 2
(-1700 3050);
DISPLAY 0.787234 (-1700 3050);
PAINT MONO (-1700 3050);
DISPLAY INVISIBLE (-1700 3050);
FORCEPROP 1 LAST BODY_TYPE PLUMBING
J 2
(-1700 3000);
DISPLAY 1.234043 (-1700 3000);
PAINT GREEN (-1700 3000);
DISPLAY INVISIBLE (-1700 3000);
FORCEPROP 1 LAST HDL_TAP TRUE
J 2
(-2025 2925);
DISPLAY 1.234043 (-2025 2925);
PAINT GREEN (-2025 2925);
DISPLAY INVISIBLE (-2025 2925);
FORCEPROP 1 LAST PATH I78
J 2
(-1700 3050);
DISPLAY 0.936170 (-1700 3050);
PAINT GREEN (-1700 3050);
DISPLAY INVISIBLE (-1700 3050);
FORCEADD TAP..6
R 2
(-1700 3100);
FORCEPROP 3 LASTPIN (-1750 3100) SIG_NAME M_M_DQ<30>
J 0
(-1740 3110);
DISPLAY 0.659574 (-1740 3110);
PAINT MONO (-1740 3110);
DISPLAY INVISIBLE (-1740 3110);
FORCEPROP 1 LASTPIN (-1750 3100) BN 30
J 2
(-1700 3110);
DISPLAY 0.617021 (-1700 3110);
PAINT PINK (-1700 3110);
FORCEPROP 2 LAST CDS_LIB mstr_standard
J 2
(-1700 3100);
DISPLAY 0.787234 (-1700 3100);
PAINT MONO (-1700 3100);
DISPLAY INVISIBLE (-1700 3100);
FORCEPROP 1 LAST BODY_TYPE PLUMBING
J 2
(-1700 3050);
DISPLAY 1.234043 (-1700 3050);
PAINT GREEN (-1700 3050);
DISPLAY INVISIBLE (-1700 3050);
FORCEPROP 1 LAST HDL_TAP TRUE
J 2
(-2025 2975);
DISPLAY 1.234043 (-2025 2975);
PAINT GREEN (-2025 2975);
DISPLAY INVISIBLE (-2025 2975);
FORCEPROP 1 LAST PATH I79
J 2
(-1700 3100);
DISPLAY 0.936170 (-1700 3100);
PAINT GREEN (-1700 3100);
DISPLAY INVISIBLE (-1700 3100);
FORCEADD TAP..6
R 2
(900 4600);
FORCEPROP 3 LASTPIN (850 4600) SIG_NAME M_M_DQS_DN<12>
J 0
(860 4610);
DISPLAY 0.659574 (860 4610);
PAINT MONO (860 4610);
DISPLAY INVISIBLE (860 4610);
FORCEPROP 1 LASTPIN (850 4600) BN 12
J 2
(900 4610);
DISPLAY 0.617021 (900 4610);
PAINT PINK (900 4610);
FORCEPROP 2 LAST CDS_LIB mstr_standard
J 0
(900 4600);
DISPLAY 0.787234 (900 4600);
PAINT MONO (900 4600);
DISPLAY INVISIBLE (900 4600);
FORCEPROP 1 LAST BODY_TYPE PLUMBING
J 2
(900 4550);
DISPLAY 1.234043 (900 4550);
PAINT GREEN (900 4550);
DISPLAY INVISIBLE (900 4550);
FORCEPROP 1 LAST HDL_TAP TRUE
J 2
(575 4475);
DISPLAY 1.234043 (575 4475);
PAINT GREEN (575 4475);
DISPLAY INVISIBLE (575 4475);
FORCEPROP 1 LAST PATH I8
J 2
(900 4600);
DISPLAY 0.936170 (900 4600);
PAINT GREEN (900 4600);
DISPLAY INVISIBLE (900 4600);
FORCEADD TAP..6
R 2
(-1700 3150);
FORCEPROP 3 LASTPIN (-1750 3150) SIG_NAME M_M_DQ<31>
J 0
(-1740 3160);
DISPLAY 0.659574 (-1740 3160);
PAINT MONO (-1740 3160);
DISPLAY INVISIBLE (-1740 3160);
FORCEPROP 1 LASTPIN (-1750 3150) BN 31
J 2
(-1700 3160);
DISPLAY 0.617021 (-1700 3160);
PAINT PINK (-1700 3160);
FORCEPROP 2 LAST CDS_LIB mstr_standard
J 2
(-1700 3150);
DISPLAY 0.787234 (-1700 3150);
PAINT MONO (-1700 3150);
DISPLAY INVISIBLE (-1700 3150);
FORCEPROP 1 LAST BODY_TYPE PLUMBING
J 2
(-1700 3100);
DISPLAY 1.234043 (-1700 3100);
PAINT GREEN (-1700 3100);
DISPLAY INVISIBLE (-1700 3100);
FORCEPROP 1 LAST HDL_TAP TRUE
J 2
(-2025 3025);
DISPLAY 1.234043 (-2025 3025);
PAINT GREEN (-2025 3025);
DISPLAY INVISIBLE (-2025 3025);
FORCEPROP 1 LAST PATH I80
J 2
(-1700 3150);
DISPLAY 0.936170 (-1700 3150);
PAINT GREEN (-1700 3150);
DISPLAY INVISIBLE (-1700 3150);
FORCEADD TAP..6
R 2
(-1700 2750);
FORCEPROP 3 LASTPIN (-1750 2750) SIG_NAME M_M_DQ<23>
J 0
(-1740 2760);
DISPLAY 0.659574 (-1740 2760);
PAINT MONO (-1740 2760);
DISPLAY INVISIBLE (-1740 2760);
FORCEPROP 1 LASTPIN (-1750 2750) BN 23
J 2
(-1700 2760);
DISPLAY 0.617021 (-1700 2760);
PAINT PINK (-1700 2760);
FORCEPROP 2 LAST CDS_LIB mstr_standard
J 2
(-1700 2750);
DISPLAY 0.787234 (-1700 2750);
PAINT MONO (-1700 2750);
DISPLAY INVISIBLE (-1700 2750);
FORCEPROP 1 LAST BODY_TYPE PLUMBING
J 2
(-1700 2700);
DISPLAY 1.234043 (-1700 2700);
PAINT GREEN (-1700 2700);
DISPLAY INVISIBLE (-1700 2700);
FORCEPROP 1 LAST HDL_TAP TRUE
J 2
(-2025 2625);
DISPLAY 1.234043 (-2025 2625);
PAINT GREEN (-2025 2625);
DISPLAY INVISIBLE (-2025 2625);
FORCEPROP 1 LAST PATH I81
J 2
(-1700 2750);
DISPLAY 0.936170 (-1700 2750);
PAINT GREEN (-1700 2750);
DISPLAY INVISIBLE (-1700 2750);
FORCEADD TAP..6
R 2
(-1700 2950);
FORCEPROP 3 LASTPIN (-1750 2950) SIG_NAME M_M_DQ<27>
J 0
(-1740 2960);
DISPLAY 0.659574 (-1740 2960);
PAINT MONO (-1740 2960);
DISPLAY INVISIBLE (-1740 2960);
FORCEPROP 1 LASTPIN (-1750 2950) BN 27
J 2
(-1700 2960);
DISPLAY 0.617021 (-1700 2960);
PAINT PINK (-1700 2960);
FORCEPROP 2 LAST CDS_LIB mstr_standard
J 2
(-1700 2950);
DISPLAY 0.787234 (-1700 2950);
PAINT MONO (-1700 2950);
DISPLAY INVISIBLE (-1700 2950);
FORCEPROP 1 LAST BODY_TYPE PLUMBING
J 2
(-1700 2900);
DISPLAY 1.234043 (-1700 2900);
PAINT GREEN (-1700 2900);
DISPLAY INVISIBLE (-1700 2900);
FORCEPROP 1 LAST HDL_TAP TRUE
J 2
(-2025 2825);
DISPLAY 1.234043 (-2025 2825);
PAINT GREEN (-2025 2825);
DISPLAY INVISIBLE (-2025 2825);
FORCEPROP 1 LAST PATH I82
J 2
(-1700 2950);
DISPLAY 0.936170 (-1700 2950);
PAINT GREEN (-1700 2950);
DISPLAY INVISIBLE (-1700 2950);
FORCEADD TAP..6
R 2
(-1700 3000);
FORCEPROP 3 LASTPIN (-1750 3000) SIG_NAME M_M_DQ<28>
J 0
(-1740 3010);
DISPLAY 0.659574 (-1740 3010);
PAINT MONO (-1740 3010);
DISPLAY INVISIBLE (-1740 3010);
FORCEPROP 1 LASTPIN (-1750 3000) BN 28
J 2
(-1700 3010);
DISPLAY 0.617021 (-1700 3010);
PAINT PINK (-1700 3010);
FORCEPROP 2 LAST CDS_LIB mstr_standard
J 2
(-1700 3000);
DISPLAY 0.787234 (-1700 3000);
PAINT MONO (-1700 3000);
DISPLAY INVISIBLE (-1700 3000);
FORCEPROP 1 LAST BODY_TYPE PLUMBING
J 2
(-1700 2950);
DISPLAY 1.234043 (-1700 2950);
PAINT GREEN (-1700 2950);
DISPLAY INVISIBLE (-1700 2950);
FORCEPROP 1 LAST HDL_TAP TRUE
J 2
(-2025 2875);
DISPLAY 1.234043 (-2025 2875);
PAINT GREEN (-2025 2875);
DISPLAY INVISIBLE (-2025 2875);
FORCEPROP 1 LAST PATH I83
J 2
(-1700 3000);
DISPLAY 0.936170 (-1700 3000);
PAINT GREEN (-1700 3000);
DISPLAY INVISIBLE (-1700 3000);
FORCEADD TAP..6
R 2
(-1700 2900);
FORCEPROP 3 LASTPIN (-1750 2900) SIG_NAME M_M_DQ<26>
J 0
(-1740 2910);
DISPLAY 0.659574 (-1740 2910);
PAINT MONO (-1740 2910);
DISPLAY INVISIBLE (-1740 2910);
FORCEPROP 1 LASTPIN (-1750 2900) BN 26
J 2
(-1700 2910);
DISPLAY 0.617021 (-1700 2910);
PAINT PINK (-1700 2910);
FORCEPROP 2 LAST CDS_LIB mstr_standard
J 2
(-1700 2900);
DISPLAY 0.787234 (-1700 2900);
PAINT MONO (-1700 2900);
DISPLAY INVISIBLE (-1700 2900);
FORCEPROP 1 LAST BODY_TYPE PLUMBING
J 2
(-1700 2850);
DISPLAY 1.234043 (-1700 2850);
PAINT GREEN (-1700 2850);
DISPLAY INVISIBLE (-1700 2850);
FORCEPROP 1 LAST HDL_TAP TRUE
J 2
(-2025 2775);
DISPLAY 1.234043 (-2025 2775);
PAINT GREEN (-2025 2775);
DISPLAY INVISIBLE (-2025 2775);
FORCEPROP 1 LAST PATH I84
J 2
(-1700 2900);
DISPLAY 0.936170 (-1700 2900);
PAINT GREEN (-1700 2900);
DISPLAY INVISIBLE (-1700 2900);
FORCEADD TAP..6
R 2
(-1700 2850);
FORCEPROP 3 LASTPIN (-1750 2850) SIG_NAME M_M_DQ<25>
J 0
(-1740 2860);
DISPLAY 0.659574 (-1740 2860);
PAINT MONO (-1740 2860);
DISPLAY INVISIBLE (-1740 2860);
FORCEPROP 1 LASTPIN (-1750 2850) BN 25
J 2
(-1700 2860);
DISPLAY 0.617021 (-1700 2860);
PAINT PINK (-1700 2860);
FORCEPROP 2 LAST CDS_LIB mstr_standard
J 2
(-1700 2850);
DISPLAY 0.787234 (-1700 2850);
PAINT MONO (-1700 2850);
DISPLAY INVISIBLE (-1700 2850);
FORCEPROP 1 LAST BODY_TYPE PLUMBING
J 2
(-1700 2800);
DISPLAY 1.234043 (-1700 2800);
PAINT GREEN (-1700 2800);
DISPLAY INVISIBLE (-1700 2800);
FORCEPROP 1 LAST HDL_TAP TRUE
J 2
(-2025 2725);
DISPLAY 1.234043 (-2025 2725);
PAINT GREEN (-2025 2725);
DISPLAY INVISIBLE (-2025 2725);
FORCEPROP 1 LAST PATH I85
J 2
(-1700 2850);
DISPLAY 0.936170 (-1700 2850);
PAINT GREEN (-1700 2850);
DISPLAY INVISIBLE (-1700 2850);
FORCEADD TAP..6
R 2
(-1700 2800);
FORCEPROP 3 LASTPIN (-1750 2800) SIG_NAME M_M_DQ<24>
J 0
(-1740 2810);
DISPLAY 0.659574 (-1740 2810);
PAINT MONO (-1740 2810);
DISPLAY INVISIBLE (-1740 2810);
FORCEPROP 1 LASTPIN (-1750 2800) BN 24
J 2
(-1700 2810);
DISPLAY 0.617021 (-1700 2810);
PAINT PINK (-1700 2810);
FORCEPROP 2 LAST CDS_LIB mstr_standard
J 2
(-1700 2800);
DISPLAY 0.787234 (-1700 2800);
PAINT MONO (-1700 2800);
DISPLAY INVISIBLE (-1700 2800);
FORCEPROP 1 LAST BODY_TYPE PLUMBING
J 2
(-1700 2750);
DISPLAY 1.234043 (-1700 2750);
PAINT GREEN (-1700 2750);
DISPLAY INVISIBLE (-1700 2750);
FORCEPROP 1 LAST HDL_TAP TRUE
J 2
(-2025 2675);
DISPLAY 1.234043 (-2025 2675);
PAINT GREEN (-2025 2675);
DISPLAY INVISIBLE (-2025 2675);
FORCEPROP 1 LAST PATH I86
J 2
(-1700 2800);
DISPLAY 0.936170 (-1700 2800);
PAINT GREEN (-1700 2800);
DISPLAY INVISIBLE (-1700 2800);
FORCEADD SCONN288_H44441003..2
(0 4300);
FORCEPROP 1 LAST LOCATION J9L1
J 0
(-400 5400);
DISPLAY 0.617021 (-400 5400);
PAINT AQUA (-400 5400);
FORCEPROP 1 LAST PART_NUMBER H44441-003
J 0
(-400 3200);
DISPLAY 0.617021 (-400 3200);
PAINT BLUE (-400 3200);
FORCEPROP 1 LAST MATERIAL SCONN
J 0
(-400 5350);
DISPLAY 0.617021 (-400 5350);
PAINT SKYBLUE (-400 5350);
FORCEPROP 2 LASTPIN (450 5150) $PN 51
J 0
(460 5160);
DISPLAY 0.617021 (460 5160);
PAINT ORANGE (460 5160);
FORCEPROP 2 LASTPIN (450 5100) $PN 52
J 0
(460 5110);
DISPLAY 0.617021 (460 5110);
PAINT ORANGE (460 5110);
FORCEPROP 2 LASTPIN (450 5050) $PN 132
J 0
(460 5060);
DISPLAY 0.617021 (460 5060);
PAINT ORANGE (460 5060);
FORCEPROP 2 LASTPIN (450 5000) $PN 133
J 0
(460 5010);
DISPLAY 0.617021 (460 5010);
PAINT ORANGE (460 5010);
FORCEPROP 2 LASTPIN (450 4950) $PN 121
J 0
(460 4960);
DISPLAY 0.617021 (460 4960);
PAINT ORANGE (460 4960);
FORCEPROP 2 LASTPIN (450 4900) $PN 122
J 0
(460 4910);
DISPLAY 0.617021 (460 4910);
PAINT ORANGE (460 4910);
FORCEPROP 2 LASTPIN (450 4850) $PN 110
J 0
(460 4860);
DISPLAY 0.617021 (460 4860);
PAINT ORANGE (460 4860);
FORCEPROP 2 LASTPIN (450 4800) $PN 111
J 0
(460 4810);
DISPLAY 0.617021 (460 4810);
PAINT ORANGE (460 4810);
FORCEPROP 2 LASTPIN (450 4750) $PN 99
J 0
(460 4760);
DISPLAY 0.617021 (460 4760);
PAINT ORANGE (460 4760);
FORCEPROP 2 LASTPIN (450 4700) $PN 100
J 0
(460 4710);
DISPLAY 0.617021 (460 4710);
PAINT ORANGE (460 4710);
FORCEPROP 2 LASTPIN (450 4650) $PN 40
J 0
(460 4660);
DISPLAY 0.617021 (460 4660);
PAINT ORANGE (460 4660);
FORCEPROP 2 LASTPIN (450 4600) $PN 41
J 0
(460 4610);
DISPLAY 0.617021 (460 4610);
PAINT ORANGE (460 4610);
FORCEPROP 2 LASTPIN (450 4550) $PN 29
J 0
(460 4560);
DISPLAY 0.617021 (460 4560);
PAINT ORANGE (460 4560);
FORCEPROP 2 LASTPIN (450 4500) $PN 30
J 0
(460 4510);
DISPLAY 0.617021 (460 4510);
PAINT ORANGE (460 4510);
FORCEPROP 2 LASTPIN (450 4450) $PN 18
J 0
(460 4460);
DISPLAY 0.617021 (460 4460);
PAINT ORANGE (460 4460);
FORCEPROP 2 LASTPIN (450 4400) $PN 19
J 0
(460 4410);
DISPLAY 0.617021 (460 4410);
PAINT ORANGE (460 4410);
FORCEPROP 2 LASTPIN (450 4350) $PN 7
J 0
(460 4360);
DISPLAY 0.617021 (460 4360);
PAINT ORANGE (460 4360);
FORCEPROP 2 LASTPIN (450 4300) $PN 8
J 0
(460 4310);
DISPLAY 0.617021 (460 4310);
PAINT ORANGE (460 4310);
FORCEPROP 2 LASTPIN (450 4250) $PN 197
J 0
(460 4260);
DISPLAY 0.617021 (460 4260);
PAINT ORANGE (460 4260);
FORCEPROP 2 LASTPIN (450 4200) $PN 196
J 0
(460 4210);
DISPLAY 0.617021 (460 4210);
PAINT ORANGE (460 4210);
FORCEPROP 2 LASTPIN (450 4150) $PN 278
J 0
(460 4160);
DISPLAY 0.617021 (460 4160);
PAINT ORANGE (460 4160);
FORCEPROP 2 LASTPIN (450 4100) $PN 277
J 0
(460 4110);
DISPLAY 0.617021 (460 4110);
PAINT ORANGE (460 4110);
FORCEPROP 2 LASTPIN (450 4050) $PN 267
J 0
(460 4060);
DISPLAY 0.617021 (460 4060);
PAINT ORANGE (460 4060);
FORCEPROP 2 LASTPIN (450 4000) $PN 266
J 0
(460 4010);
DISPLAY 0.617021 (460 4010);
PAINT ORANGE (460 4010);
FORCEPROP 2 LASTPIN (450 3950) $PN 256
J 0
(460 3960);
DISPLAY 0.617021 (460 3960);
PAINT ORANGE (460 3960);
FORCEPROP 2 LASTPIN (450 3900) $PN 255
J 0
(460 3910);
DISPLAY 0.617021 (460 3910);
PAINT ORANGE (460 3910);
FORCEPROP 2 LASTPIN (450 3850) $PN 245
J 0
(460 3860);
DISPLAY 0.617021 (460 3860);
PAINT ORANGE (460 3860);
FORCEPROP 2 LASTPIN (450 3800) $PN 244
J 0
(460 3810);
DISPLAY 0.617021 (460 3810);
PAINT ORANGE (460 3810);
FORCEPROP 2 LASTPIN (450 3700) $PN 185
J 0
(460 3710);
DISPLAY 0.617021 (460 3710);
PAINT ORANGE (460 3710);
FORCEPROP 2 LASTPIN (450 3650) $PN 175
J 0
(460 3660);
DISPLAY 0.617021 (460 3660);
PAINT ORANGE (460 3660);
FORCEPROP 2 LASTPIN (450 3600) $PN 174
J 0
(460 3610);
DISPLAY 0.617021 (460 3610);
PAINT ORANGE (460 3610);
FORCEPROP 2 LASTPIN (450 3500) $PN 163
J 0
(460 3510);
DISPLAY 0.617021 (460 3510);
PAINT ORANGE (460 3510);
FORCEPROP 2 LASTPIN (450 3400) $PN 152
J 0
(460 3410);
DISPLAY 0.617021 (460 3410);
PAINT ORANGE (460 3410);
FORCEPROP 2 LASTPIN (450 3550) $PN 164
J 0
(460 3560);
DISPLAY 0.617021 (460 3560);
PAINT ORANGE (460 3560);
FORCEPROP 2 LASTPIN (450 3750) $PN 186
J 0
(460 3760);
DISPLAY 0.617021 (460 3760);
PAINT ORANGE (460 3760);
FORCEPROP 2 LASTPIN (450 3450) $PN 153
J 0
(460 3460);
DISPLAY 0.617021 (460 3460);
PAINT ORANGE (460 3460);
FORCEPROP 0 LAST BOM_SS NOPOP
J 0
(-261 5342);
DISPLAY 1.021277 (-261 5342);
PAINT BROWN (-261 5342);
DISPLAY BOTH (-261 5342);
FORCEPROP 1 LAST PACK_TYPE PIP
J 0
(-400 5450);
PAINT SKYBLUE (-400 5450);
DISPLAY INVISIBLE (-400 5450);
FORCEPROP 2 LAST SEC_TYPE PIP
J 0
(-400 5450);
DISPLAY 1.021277 (-400 5450);
PAINT ORANGE (-400 5450);
DISPLAY INVISIBLE (-400 5450);
FORCEPROP 2 LAST CDS_LIB mstr_sconn
J 0
(0 4300);
PAINT ORANGE (0 4300);
DISPLAY INVISIBLE (0 4300);
FORCEPROP 2 LAST BOM_COST DDR4_CH_M
J 0
(0 4300);
PAINT ORANGE (0 4300);
DISPLAY INVISIBLE (0 4300);
FORCEPROP 2 LAST SEC 2
J 0
(-400 5450);
DISPLAY 0.680851 (-400 5450);
PAINT MONO (-400 5450);
DISPLAY INVISIBLE (-400 5450);
FORCEPROP 2 LAST CDS_LOCATION J9L1
J 0
(-400 5400);
DISPLAY 0.617021 (-400 5400);
PAINT AQUA (-400 5400);
DISPLAY INVISIBLE (-400 5400);
FORCEPROP 1 LAST PATH I87
J 0
(0 5350);
PAINT GREEN (0 5350);
DISPLAY INVISIBLE (0 5350);
FORCEPROP 2 LAST ROOM DDR4_CH_M
J 0
(-400 5500);
PAINT ORANGE (-400 5500);
DISPLAY INVISIBLE (-400 5500);
FORCEADD TAP..6
R 2
(-1700 2500);
FORCEPROP 3 LASTPIN (-1750 2500) SIG_NAME M_M_DQ<18>
J 0
(-1740 2510);
DISPLAY 0.659574 (-1740 2510);
PAINT MONO (-1740 2510);
DISPLAY INVISIBLE (-1740 2510);
FORCEPROP 1 LASTPIN (-1750 2500) BN 18
J 2
(-1700 2510);
DISPLAY 0.617021 (-1700 2510);
PAINT PINK (-1700 2510);
FORCEPROP 2 LAST CDS_LIB mstr_standard
J 2
(-1700 2500);
DISPLAY 0.787234 (-1700 2500);
PAINT MONO (-1700 2500);
DISPLAY INVISIBLE (-1700 2500);
FORCEPROP 1 LAST BODY_TYPE PLUMBING
J 2
(-1700 2450);
DISPLAY 1.234043 (-1700 2450);
PAINT GREEN (-1700 2450);
DISPLAY INVISIBLE (-1700 2450);
FORCEPROP 1 LAST HDL_TAP TRUE
J 2
(-2025 2375);
DISPLAY 1.234043 (-2025 2375);
PAINT GREEN (-2025 2375);
DISPLAY INVISIBLE (-2025 2375);
FORCEPROP 1 LAST PATH I88
J 2
(-1700 2500);
DISPLAY 0.936170 (-1700 2500);
PAINT GREEN (-1700 2500);
DISPLAY INVISIBLE (-1700 2500);
FORCEADD TAP..6
R 2
(-1700 2700);
FORCEPROP 3 LASTPIN (-1750 2700) SIG_NAME M_M_DQ<22>
J 0
(-1740 2710);
DISPLAY 0.659574 (-1740 2710);
PAINT MONO (-1740 2710);
DISPLAY INVISIBLE (-1740 2710);
FORCEPROP 1 LASTPIN (-1750 2700) BN 22
J 2
(-1700 2710);
DISPLAY 0.617021 (-1700 2710);
PAINT PINK (-1700 2710);
FORCEPROP 2 LAST CDS_LIB mstr_standard
J 2
(-1700 2700);
DISPLAY 0.787234 (-1700 2700);
PAINT MONO (-1700 2700);
DISPLAY INVISIBLE (-1700 2700);
FORCEPROP 1 LAST BODY_TYPE PLUMBING
J 2
(-1700 2650);
DISPLAY 1.234043 (-1700 2650);
PAINT GREEN (-1700 2650);
DISPLAY INVISIBLE (-1700 2650);
FORCEPROP 1 LAST HDL_TAP TRUE
J 2
(-2025 2575);
DISPLAY 1.234043 (-2025 2575);
PAINT GREEN (-2025 2575);
DISPLAY INVISIBLE (-2025 2575);
FORCEPROP 1 LAST PATH I89
J 2
(-1700 2700);
DISPLAY 0.936170 (-1700 2700);
PAINT GREEN (-1700 2700);
DISPLAY INVISIBLE (-1700 2700);
FORCEADD PVTT_KLM..1
(-1150 2700);
FORCEPROP 3 LASTPIN (-1150 2650) SIG_NAME PVTT_KLM\g
J 0
(-1140 2660);
DISPLAY 0.659574 (-1140 2660);
PAINT MONO (-1140 2660);
DISPLAY INVISIBLE (-1140 2660);
FORCEPROP 1 LAST VOLTAGE 0.6V
J 0
(-1195 2657);
DISPLAY 0.340426 (-1195 2657);
PAINT SKYBLUE (-1195 2657);
DISPLAY INVISIBLE (-1195 2657);
FORCEPROP 2 LAST BOM_COST PROC
J 0
(-1150 2705);
PAINT ORANGE (-1150 2705);
DISPLAY INVISIBLE (-1150 2705);
FORCEPROP 2 LAST CDS_LIB mstr_symbols
J 0
(-1150 2700);
PAINT ORANGE (-1150 2700);
DISPLAY INVISIBLE (-1150 2700);
FORCEPROP 1 LAST BODY_TYPE PLUMBING
J 0
(-1195 2657);
DISPLAY 0.340426 (-1195 2657);
PAINT GREEN (-1195 2657);
DISPLAY INVISIBLE (-1195 2657);
FORCEPROP 1 LAST PATH I9
J 0
(-1100 2725);
DISPLAY 0.872340 (-1100 2725);
PAINT AQUA (-1100 2725);
DISPLAY INVISIBLE (-1100 2725);
FORCEPROP 2 LAST ROOM PROC
J 0
(-1150 2800);
DISPLAY 0.787234 (-1150 2800);
PAINT ORANGE (-1150 2800);
DISPLAY INVISIBLE (-1150 2800);
FORCEPROP 1 LAST HDL_POWER PVTT_KLM
J 1
(-1150 2750);
DISPLAY 0.872340 (-1150 2750);
PAINT GREEN (-1150 2750);
DISPLAY INVISIBLE (-1150 2750);
FORCEADD TAP..6
R 2
(-1700 2650);
FORCEPROP 3 LASTPIN (-1750 2650) SIG_NAME M_M_DQ<21>
J 0
(-1740 2660);
DISPLAY 0.659574 (-1740 2660);
PAINT MONO (-1740 2660);
DISPLAY INVISIBLE (-1740 2660);
FORCEPROP 1 LASTPIN (-1750 2650) BN 21
J 2
(-1700 2660);
DISPLAY 0.617021 (-1700 2660);
PAINT PINK (-1700 2660);
FORCEPROP 2 LAST CDS_LIB mstr_standard
J 2
(-1700 2650);
DISPLAY 0.787234 (-1700 2650);
PAINT MONO (-1700 2650);
DISPLAY INVISIBLE (-1700 2650);
FORCEPROP 1 LAST BODY_TYPE PLUMBING
J 2
(-1700 2600);
DISPLAY 1.234043 (-1700 2600);
PAINT GREEN (-1700 2600);
DISPLAY INVISIBLE (-1700 2600);
FORCEPROP 1 LAST HDL_TAP TRUE
J 2
(-2025 2525);
DISPLAY 1.234043 (-2025 2525);
PAINT GREEN (-2025 2525);
DISPLAY INVISIBLE (-2025 2525);
FORCEPROP 1 LAST PATH I90
J 2
(-1700 2650);
DISPLAY 0.936170 (-1700 2650);
PAINT GREEN (-1700 2650);
DISPLAY INVISIBLE (-1700 2650);
FORCEADD TAP..6
R 2
(-1700 2550);
FORCEPROP 3 LASTPIN (-1750 2550) SIG_NAME M_M_DQ<19>
J 0
(-1740 2560);
DISPLAY 0.659574 (-1740 2560);
PAINT MONO (-1740 2560);
DISPLAY INVISIBLE (-1740 2560);
FORCEPROP 1 LASTPIN (-1750 2550) BN 19
J 2
(-1700 2560);
DISPLAY 0.617021 (-1700 2560);
PAINT PINK (-1700 2560);
FORCEPROP 2 LAST CDS_LIB mstr_standard
J 2
(-1700 2550);
DISPLAY 0.787234 (-1700 2550);
PAINT MONO (-1700 2550);
DISPLAY INVISIBLE (-1700 2550);
FORCEPROP 1 LAST BODY_TYPE PLUMBING
J 2
(-1700 2500);
DISPLAY 1.234043 (-1700 2500);
PAINT GREEN (-1700 2500);
DISPLAY INVISIBLE (-1700 2500);
FORCEPROP 1 LAST HDL_TAP TRUE
J 2
(-2025 2425);
DISPLAY 1.234043 (-2025 2425);
PAINT GREEN (-2025 2425);
DISPLAY INVISIBLE (-2025 2425);
FORCEPROP 1 LAST PATH I91
J 2
(-1700 2550);
DISPLAY 0.936170 (-1700 2550);
PAINT GREEN (-1700 2550);
DISPLAY INVISIBLE (-1700 2550);
FORCEADD TAP..6
R 2
(-1700 2600);
FORCEPROP 3 LASTPIN (-1750 2600) SIG_NAME M_M_DQ<20>
J 0
(-1740 2610);
DISPLAY 0.659574 (-1740 2610);
PAINT MONO (-1740 2610);
DISPLAY INVISIBLE (-1740 2610);
FORCEPROP 1 LASTPIN (-1750 2600) BN 20
J 2
(-1700 2610);
DISPLAY 0.617021 (-1700 2610);
PAINT PINK (-1700 2610);
FORCEPROP 2 LAST CDS_LIB mstr_standard
J 2
(-1700 2600);
DISPLAY 0.787234 (-1700 2600);
PAINT MONO (-1700 2600);
DISPLAY INVISIBLE (-1700 2600);
FORCEPROP 1 LAST BODY_TYPE PLUMBING
J 2
(-1700 2550);
DISPLAY 1.234043 (-1700 2550);
PAINT GREEN (-1700 2550);
DISPLAY INVISIBLE (-1700 2550);
FORCEPROP 1 LAST HDL_TAP TRUE
J 2
(-2025 2475);
DISPLAY 1.234043 (-2025 2475);
PAINT GREEN (-2025 2475);
DISPLAY INVISIBLE (-2025 2475);
FORCEPROP 1 LAST PATH I92
J 2
(-1700 2600);
DISPLAY 0.936170 (-1700 2600);
PAINT GREEN (-1700 2600);
DISPLAY INVISIBLE (-1700 2600);
FORCEADD TAP..6
R 2
(-1700 2250);
FORCEPROP 3 LASTPIN (-1750 2250) SIG_NAME M_M_DQ<13>
J 0
(-1740 2260);
DISPLAY 0.659574 (-1740 2260);
PAINT MONO (-1740 2260);
DISPLAY INVISIBLE (-1740 2260);
FORCEPROP 1 LASTPIN (-1750 2250) BN 13
J 2
(-1700 2260);
DISPLAY 0.617021 (-1700 2260);
PAINT PINK (-1700 2260);
FORCEPROP 2 LAST CDS_LIB mstr_standard
J 2
(-1700 2250);
DISPLAY 0.787234 (-1700 2250);
PAINT MONO (-1700 2250);
DISPLAY INVISIBLE (-1700 2250);
FORCEPROP 1 LAST BODY_TYPE PLUMBING
J 2
(-1700 2200);
DISPLAY 1.234043 (-1700 2200);
PAINT GREEN (-1700 2200);
DISPLAY INVISIBLE (-1700 2200);
FORCEPROP 1 LAST HDL_TAP TRUE
J 2
(-2025 2125);
DISPLAY 1.234043 (-2025 2125);
PAINT GREEN (-2025 2125);
DISPLAY INVISIBLE (-2025 2125);
FORCEPROP 1 LAST PATH I93
J 2
(-1700 2250);
DISPLAY 0.936170 (-1700 2250);
PAINT GREEN (-1700 2250);
DISPLAY INVISIBLE (-1700 2250);
FORCEADD TAP..6
R 2
(-1700 2400);
FORCEPROP 3 LASTPIN (-1750 2400) SIG_NAME M_M_DQ<16>
J 0
(-1740 2410);
DISPLAY 0.659574 (-1740 2410);
PAINT MONO (-1740 2410);
DISPLAY INVISIBLE (-1740 2410);
FORCEPROP 1 LASTPIN (-1750 2400) BN 16
J 2
(-1700 2410);
DISPLAY 0.617021 (-1700 2410);
PAINT PINK (-1700 2410);
FORCEPROP 2 LAST CDS_LIB mstr_standard
J 2
(-1700 2400);
DISPLAY 0.787234 (-1700 2400);
PAINT MONO (-1700 2400);
DISPLAY INVISIBLE (-1700 2400);
FORCEPROP 1 LAST BODY_TYPE PLUMBING
J 2
(-1700 2350);
DISPLAY 1.234043 (-1700 2350);
PAINT GREEN (-1700 2350);
DISPLAY INVISIBLE (-1700 2350);
FORCEPROP 1 LAST HDL_TAP TRUE
J 2
(-2025 2275);
DISPLAY 1.234043 (-2025 2275);
PAINT GREEN (-2025 2275);
DISPLAY INVISIBLE (-2025 2275);
FORCEPROP 1 LAST PATH I94
J 2
(-1700 2400);
DISPLAY 0.936170 (-1700 2400);
PAINT GREEN (-1700 2400);
DISPLAY INVISIBLE (-1700 2400);
FORCEADD TAP..6
R 2
(-1700 2450);
FORCEPROP 3 LASTPIN (-1750 2450) SIG_NAME M_M_DQ<17>
J 0
(-1740 2460);
DISPLAY 0.659574 (-1740 2460);
PAINT MONO (-1740 2460);
DISPLAY INVISIBLE (-1740 2460);
FORCEPROP 1 LASTPIN (-1750 2450) BN 17
J 2
(-1700 2460);
DISPLAY 0.617021 (-1700 2460);
PAINT PINK (-1700 2460);
FORCEPROP 2 LAST CDS_LIB mstr_standard
J 2
(-1700 2450);
DISPLAY 0.787234 (-1700 2450);
PAINT MONO (-1700 2450);
DISPLAY INVISIBLE (-1700 2450);
FORCEPROP 1 LAST BODY_TYPE PLUMBING
J 2
(-1700 2400);
DISPLAY 1.234043 (-1700 2400);
PAINT GREEN (-1700 2400);
DISPLAY INVISIBLE (-1700 2400);
FORCEPROP 1 LAST HDL_TAP TRUE
J 2
(-2025 2325);
DISPLAY 1.234043 (-2025 2325);
PAINT GREEN (-2025 2325);
DISPLAY INVISIBLE (-2025 2325);
FORCEPROP 1 LAST PATH I95
J 2
(-1700 2450);
DISPLAY 0.936170 (-1700 2450);
PAINT GREEN (-1700 2450);
DISPLAY INVISIBLE (-1700 2450);
FORCEADD TAP..6
R 2
(-1700 2300);
FORCEPROP 3 LASTPIN (-1750 2300) SIG_NAME M_M_DQ<14>
J 0
(-1740 2310);
DISPLAY 0.659574 (-1740 2310);
PAINT MONO (-1740 2310);
DISPLAY INVISIBLE (-1740 2310);
FORCEPROP 1 LASTPIN (-1750 2300) BN 14
J 2
(-1700 2310);
DISPLAY 0.617021 (-1700 2310);
PAINT PINK (-1700 2310);
FORCEPROP 2 LAST CDS_LIB mstr_standard
J 2
(-1700 2300);
DISPLAY 0.787234 (-1700 2300);
PAINT MONO (-1700 2300);
DISPLAY INVISIBLE (-1700 2300);
FORCEPROP 1 LAST BODY_TYPE PLUMBING
J 2
(-1700 2250);
DISPLAY 1.234043 (-1700 2250);
PAINT GREEN (-1700 2250);
DISPLAY INVISIBLE (-1700 2250);
FORCEPROP 1 LAST HDL_TAP TRUE
J 2
(-2025 2175);
DISPLAY 1.234043 (-2025 2175);
PAINT GREEN (-2025 2175);
DISPLAY INVISIBLE (-2025 2175);
FORCEPROP 1 LAST PATH I96
J 2
(-1700 2300);
DISPLAY 0.936170 (-1700 2300);
PAINT GREEN (-1700 2300);
DISPLAY INVISIBLE (-1700 2300);
FORCEADD TAP..6
R 2
(-1700 2350);
FORCEPROP 3 LASTPIN (-1750 2350) SIG_NAME M_M_DQ<15>
J 0
(-1740 2360);
DISPLAY 0.659574 (-1740 2360);
PAINT MONO (-1740 2360);
DISPLAY INVISIBLE (-1740 2360);
FORCEPROP 1 LASTPIN (-1750 2350) BN 15
J 2
(-1700 2360);
DISPLAY 0.617021 (-1700 2360);
PAINT PINK (-1700 2360);
FORCEPROP 2 LAST CDS_LIB mstr_standard
J 2
(-1700 2350);
DISPLAY 0.787234 (-1700 2350);
PAINT MONO (-1700 2350);
DISPLAY INVISIBLE (-1700 2350);
FORCEPROP 1 LAST BODY_TYPE PLUMBING
J 2
(-1700 2300);
DISPLAY 1.234043 (-1700 2300);
PAINT GREEN (-1700 2300);
DISPLAY INVISIBLE (-1700 2300);
FORCEPROP 1 LAST HDL_TAP TRUE
J 2
(-2025 2225);
DISPLAY 1.234043 (-2025 2225);
PAINT GREEN (-2025 2225);
DISPLAY INVISIBLE (-2025 2225);
FORCEPROP 1 LAST PATH I97
J 2
(-1700 2350);
DISPLAY 0.936170 (-1700 2350);
PAINT GREEN (-1700 2350);
DISPLAY INVISIBLE (-1700 2350);
FORCEADD TAP..6
R 2
(-1700 2000);
FORCEPROP 3 LASTPIN (-1750 2000) SIG_NAME M_M_DQ<8>
J 0
(-1740 2010);
DISPLAY 0.659574 (-1740 2010);
PAINT MONO (-1740 2010);
DISPLAY INVISIBLE (-1740 2010);
FORCEPROP 1 LASTPIN (-1750 2000) BN 8
J 2
(-1700 2010);
DISPLAY 0.617021 (-1700 2010);
PAINT PINK (-1700 2010);
FORCEPROP 2 LAST CDS_LIB mstr_standard
J 2
(-1700 2000);
DISPLAY 0.787234 (-1700 2000);
PAINT MONO (-1700 2000);
DISPLAY INVISIBLE (-1700 2000);
FORCEPROP 1 LAST BODY_TYPE PLUMBING
J 2
(-1700 1950);
DISPLAY 1.234043 (-1700 1950);
PAINT GREEN (-1700 1950);
DISPLAY INVISIBLE (-1700 1950);
FORCEPROP 1 LAST HDL_TAP TRUE
J 2
(-2025 1875);
DISPLAY 1.234043 (-2025 1875);
PAINT GREEN (-2025 1875);
DISPLAY INVISIBLE (-2025 1875);
FORCEPROP 1 LAST PATH I98
J 2
(-1700 2000);
DISPLAY 0.936170 (-1700 2000);
PAINT GREEN (-1700 2000);
DISPLAY INVISIBLE (-1700 2000);
FORCEADD TAP..6
R 2
(-1700 2100);
FORCEPROP 3 LASTPIN (-1750 2100) SIG_NAME M_M_DQ<10>
J 0
(-1740 2110);
DISPLAY 0.659574 (-1740 2110);
PAINT MONO (-1740 2110);
DISPLAY INVISIBLE (-1740 2110);
FORCEPROP 1 LASTPIN (-1750 2100) BN 10
J 2
(-1700 2110);
DISPLAY 0.617021 (-1700 2110);
PAINT PINK (-1700 2110);
FORCEPROP 2 LAST CDS_LIB mstr_standard
J 2
(-1700 2100);
DISPLAY 0.787234 (-1700 2100);
PAINT MONO (-1700 2100);
DISPLAY INVISIBLE (-1700 2100);
FORCEPROP 1 LAST BODY_TYPE PLUMBING
J 2
(-1700 2050);
DISPLAY 1.234043 (-1700 2050);
PAINT GREEN (-1700 2050);
DISPLAY INVISIBLE (-1700 2050);
FORCEPROP 1 LAST HDL_TAP TRUE
J 2
(-2025 1975);
DISPLAY 1.234043 (-2025 1975);
PAINT GREEN (-2025 1975);
DISPLAY INVISIBLE (-2025 1975);
FORCEPROP 1 LAST PATH I99
J 2
(-1700 2100);
DISPLAY 0.936170 (-1700 2100);
PAINT GREEN (-1700 2100);
DISPLAY INVISIBLE (-1700 2100);
FORCEADD INTEL_CORP_BPAGE..1
(2650 500);
FORCEPROP 1 LAST CDS_CON_LAST_MODIFIED Fri Jun 16 17:48:33 2017
J 0
(1225 825);
DISPLAY 0.787234 (1225 825);
PAINT ORANGE (1225 825);
DISPLAY INVISIBLE (1225 825);
FORCEPROP 1 LAST CUSTOM_TXT_CDS <CURRENT_DESIGN_SHEET> OF <TOTAL_DESIGN_SHEETS>
J 0
(2150 525);
PAINT ORANGE (2150 525);
FORCEPROP 1 LAST CUSTOM_TXT_CDS <CON_LAST_MODIFIED>
J 0
(-1350 600);
PAINT ORANGE (-1350 600);
FORCEPROP 2 LAST CUSTOM_TXT_CDS <XR_PAGE_TITLE>
J 0
(-5240 5750);
DISPLAY 0.638298 (-5240 5750);
PAINT PINK (-5240 5750);
DISPLAY INVISIBLE (-5240 5750);
FORCEPROP 1 LAST SCH_TITLE CPU1 DDR4 CH M DIMM1
J 0
(-5300 550);
DISPLAY 1.212766 (-5300 550);
PAINT WHITE (-5300 550);
FORCEPROP 2 LAST PAGE_BORDER TRUE
J 0
(-5240 5750);
DISPLAY 0.680851 (-5240 5750);
PAINT PINK (-5240 5750);
DISPLAY INVISIBLE (-5240 5750);
FORCEPROP 2 LAST CDS_LIB mstr_symbols
J 0
(2650 500);
DISPLAY 0.787234 (2650 500);
PAINT MONO (2650 500);
DISPLAY INVISIBLE (2650 500);
FORCEPROP 1 LAST COMMENT_BODY TRUE
J 0
(2660 510);
DISPLAY 0.382979 (2660 510);
PAINT GREEN (2660 510);
DISPLAY INVISIBLE (2660 510);
FORCEPROP 2 LAST CDS_XR_PAGE_TITLE CR-88 : @BASEBOARD_FAB2_LIB.BASEBOARD_FAB2(SCH_1):PAGE88
J 0
(-5240 5750);
DISPLAY 0.638298 (-5240 5750);
PAINT PINK (-5240 5750);
DISPLAY INVISIBLE (-5240 5750);
FORCEADD BOM_NOTE..1
(-5025 5300);
FORCEPROP 0 LAST L1 UNSTUFF FOR SKU B
J 0
(-5175 5200);
DISPLAY 1.063830 (-5175 5200);
PAINT WHITE (-5175 5200);
FORCEPROP 2 LAST BOM_COST SB
J 0
(-5175 5275);
DISPLAY 1.361702 (-5175 5275);
PAINT ORANGE (-5175 5275);
DISPLAY INVISIBLE (-5175 5275);
FORCEPROP 2 LAST CDS_LIB mstr_symbols
J 0
(-5025 5300);
PAINT ORANGE (-5025 5300);
DISPLAY INVISIBLE (-5025 5300);
FORCEPROP 1 LAST COMMENT_BODY TRUE
J 0
(-5000 5400);
DISPLAY 1.319149 (-5000 5400);
PAINT ORANGE (-5000 5400);
DISPLAY INVISIBLE (-5000 5400);
FORCEPROP 2 LAST ROOM SB_HEADERS
J 0
(-5175 5275);
DISPLAY 1.361702 (-5175 5275);
PAINT ORANGE (-5175 5275);
DISPLAY INVISIBLE (-5175 5275);
WIRE 16 -1 (-1350 2500)(-1350 2400);
WIRE 16 -1 (-1350 2400)(-1000 2400);
WIRE 16 -1 (-1000 2350)(-1000 2400);
WIRE 16 -1 (-1000 2400)(-800 2400);
WIRE 16 -1 (-1000 2300)(-1000 2350);
WIRE 16 -1 (-1000 2350)(-800 2350);
WIRE 16 -1 (-1000 2250)(-1000 2300);
WIRE 16 -1 (-1000 2300)(-800 2300);
WIRE 16 -1 (-1000 2200)(-1000 2250);
WIRE 16 -1 (-1000 2250)(-800 2250);
WIRE 16 -1 (-1000 2150)(-1000 2200);
WIRE 16 -1 (-1000 2200)(-800 2200);
WIRE 16 -1 (-1000 2100)(-1000 2150);
WIRE 16 -1 (-1000 2150)(-800 2150);
WIRE 16 -1 (-1000 2050)(-1000 2100);
WIRE 16 -1 (-1000 2100)(-800 2100);
WIRE 16 -1 (-1000 2000)(-1000 2050);
WIRE 16 -1 (-1000 2050)(-800 2050);
WIRE 16 -1 (-1000 1950)(-1000 2000);
WIRE 16 -1 (-1000 2000)(-800 2000);
WIRE 16 -1 (-1000 1900)(-1000 1950);
WIRE 16 -1 (-1000 1950)(-800 1950);
WIRE 16 -1 (-1000 1850)(-1000 1900);
WIRE 16 -1 (-1000 1900)(-800 1900);
WIRE 16 -1 (-1000 1800)(-1000 1850);
WIRE 16 -1 (-1000 1850)(-800 1850);
WIRE 16 -1 (-1000 1750)(-1000 1800);
WIRE 16 -1 (-1000 1800)(-800 1800);
WIRE 16 -1 (-1000 1700)(-1000 1750);
WIRE 16 -1 (-1000 1750)(-800 1750);
WIRE 16 -1 (-1000 1650)(-1000 1700);
WIRE 16 -1 (-1000 1700)(-800 1700);
WIRE 16 -1 (-1000 1600)(-1000 1650);
WIRE 16 -1 (-1000 1650)(-800 1650);
WIRE 16 -1 (-1000 1550)(-1000 1600);
WIRE 16 -1 (-1000 1600)(-800 1600);
WIRE 16 -1 (-1000 1500)(-1000 1550);
WIRE 16 -1 (-1000 1550)(-800 1550);
WIRE 16 -1 (-1000 1450)(-1000 1500);
WIRE 16 -1 (-1000 1500)(-800 1500);
WIRE 16 -1 (-1000 1400)(-1000 1450);
WIRE 16 -1 (-1000 1450)(-800 1450);
WIRE 16 -1 (-1000 1350)(-1000 1400);
WIRE 16 -1 (-1000 1400)(-800 1400);
WIRE 16 -1 (-1000 1300)(-1000 1350);
WIRE 16 -1 (-1000 1350)(-800 1350);
WIRE 16 -1 (-1000 1250)(-1000 1300);
WIRE 16 -1 (-1000 1300)(-800 1300);
WIRE 16 -1 (-1000 1200)(-1000 1250);
WIRE 16 -1 (-1000 1250)(-800 1250);
WIRE 16 -1 (-1000 1150)(-1000 1200);
WIRE 16 -1 (-1000 1200)(-800 1200);
WIRE 16 -1 (-1000 1150)(-800 1150);
WIRE 16 -1 (2500 1150)(2500 1250);
WIRE 16 -1 (2500 1250)(2500 1300);
WIRE 16 -1 (2500 1250)(2300 1250);
WIRE 16 -1 (2500 1300)(2500 1350);
WIRE 16 -1 (2500 1300)(2300 1300);
WIRE 16 -1 (2500 1350)(2500 1400);
WIRE 16 -1 (2500 1350)(2300 1350);
WIRE 16 -1 (2500 1400)(2500 1450);
WIRE 16 -1 (2500 1400)(2300 1400);
WIRE 16 -1 (2500 1450)(2500 1500);
WIRE 16 -1 (2500 1450)(2300 1450);
WIRE 16 -1 (2500 1500)(2500 1550);
WIRE 16 -1 (2500 1500)(2300 1500);
WIRE 16 -1 (2500 1550)(2500 1600);
WIRE 16 -1 (2500 1550)(2300 1550);
WIRE 16 -1 (2500 1600)(2500 1650);
WIRE 16 -1 (2500 1600)(2300 1600);
WIRE 16 -1 (2500 1650)(2500 1700);
WIRE 16 -1 (2500 1650)(2300 1650);
WIRE 16 -1 (2500 1700)(2500 1750);
WIRE 16 -1 (2500 1700)(2300 1700);
WIRE 16 -1 (2500 1750)(2500 1800);
WIRE 16 -1 (2500 1750)(2300 1750);
WIRE 16 -1 (2500 1800)(2500 1850);
WIRE 16 -1 (2500 1800)(2300 1800);
WIRE 16 -1 (2500 1850)(2500 1900);
WIRE 16 -1 (2500 1850)(2300 1850);
WIRE 16 -1 (2500 1900)(2500 1950);
WIRE 16 -1 (2500 1900)(2300 1900);
WIRE 16 -1 (2500 1950)(2500 2000);
WIRE 16 -1 (2500 1950)(2300 1950);
WIRE 16 -1 (2500 2000)(2500 2050);
WIRE 16 -1 (2500 2000)(2300 2000);
WIRE 16 -1 (2500 2050)(2500 2100);
WIRE 16 -1 (2500 2050)(2300 2050);
WIRE 16 -1 (2500 2100)(2500 2150);
WIRE 16 -1 (2500 2100)(2300 2100);
WIRE 16 -1 (2500 2150)(2500 2200);
WIRE 16 -1 (2500 2150)(2300 2150);
WIRE 16 -1 (2500 2200)(2500 2250);
WIRE 16 -1 (2500 2200)(2300 2200);
WIRE 16 -1 (2500 2250)(2500 2300);
WIRE 16 -1 (2500 2250)(2300 2250);
WIRE 16 -1 (2500 2300)(2500 2350);
WIRE 16 -1 (2500 2300)(2300 2300);
WIRE 16 -1 (2500 2350)(2500 2400);
WIRE 16 -1 (2500 2350)(2300 2350);
WIRE 16 -1 (2500 2400)(2500 2450);
WIRE 16 -1 (2500 2400)(2300 2400);
WIRE 16 -1 (2500 2450)(2500 2500);
WIRE 16 -1 (2500 2450)(2300 2450);
WIRE 16 -1 (2500 2500)(2500 2550);
WIRE 16 -1 (2500 2500)(2300 2500);
WIRE 16 -1 (2500 2550)(2500 2600);
WIRE 16 -1 (2500 2550)(2300 2550);
WIRE 16 -1 (2500 2600)(2500 2650);
WIRE 16 -1 (2500 2600)(2300 2600);
WIRE 16 -1 (2500 2650)(2500 2700);
WIRE 16 -1 (2500 2650)(2300 2650);
WIRE 16 -1 (2500 2700)(2500 2750);
WIRE 16 -1 (2500 2700)(2300 2700);
WIRE 16 -1 (2500 2750)(2500 2800);
WIRE 16 -1 (2500 2750)(2300 2750);
WIRE 16 -1 (2500 2800)(2500 2850);
WIRE 16 -1 (2500 2800)(2300 2800);
WIRE 16 -1 (2500 2850)(2500 2900);
WIRE 16 -1 (2500 2850)(2300 2850);
WIRE 16 -1 (2500 2900)(2500 2950);
WIRE 16 -1 (2500 2900)(2300 2900);
WIRE 16 -1 (2500 2950)(2500 3000);
WIRE 16 -1 (2500 2950)(2300 2950);
WIRE 16 -1 (2500 3000)(2500 3050);
WIRE 16 -1 (2500 3000)(2300 3000);
WIRE 16 -1 (2500 3050)(2500 3100);
WIRE 16 -1 (2500 3050)(2300 3050);
WIRE 16 -1 (2500 3100)(2500 3150);
WIRE 16 -1 (2500 3100)(2300 3100);
WIRE 16 -1 (2500 3150)(2500 3200);
WIRE 16 -1 (2500 3150)(2300 3150);
WIRE 16 -1 (2500 3200)(2500 3250);
WIRE 16 -1 (2500 3200)(2300 3200);
WIRE 16 -1 (2500 3250)(2500 3300);
WIRE 16 -1 (2500 3250)(2300 3250);
WIRE 16 -1 (2500 3300)(2500 3350);
WIRE 16 -1 (2500 3300)(2300 3300);
WIRE 16 -1 (2500 3350)(2500 3400);
WIRE 16 -1 (2500 3350)(2300 3350);
WIRE 16 -1 (2500 3400)(2500 3450);
WIRE 16 -1 (2500 3400)(2300 3400);
WIRE 16 -1 (2500 3450)(2500 3500);
WIRE 16 -1 (2500 3450)(2300 3450);
WIRE 16 -1 (2500 3500)(2500 3550);
WIRE 16 -1 (2500 3500)(2300 3500);
WIRE 16 -1 (2500 3550)(2300 3550);
WIRE 16 -1 (-5200 1850)(-5200 1775);
WIRE 16 -1 (-2950 1850)(-5200 1850);
WIRE 16 -1 (-4650 1300)(-4650 1200);
WIRE 16 -1 (-5200 1950)(-5200 2050);
WIRE 16 -1 (-3100 1950)(-5200 1950);
WIRE 16 -1 (-3100 1900)(-3100 1950);
WIRE 16 -1 (-2950 1950)(-3100 1950);
WIRE 16 -1 (-3100 1900)(-3100 1800);
WIRE 16 -1 (-2950 1900)(-3100 1900);
WIRE 16 -1 (-2950 1800)(-3100 1800);
WIRE 16 -1 (-1000 2975)(-1000 2850);
WIRE 16 -1 (-1000 2800)(-1000 2850);
WIRE 16 -1 (-1000 2850)(-800 2850);
WIRE 16 -1 (-1000 2750)(-1000 2800);
WIRE 16 -1 (-1000 2800)(-800 2800);
WIRE 16 -1 (-1000 2700)(-1000 2750);
WIRE 16 -1 (-1000 2750)(-800 2750);
WIRE 16 -1 (-1000 2650)(-1000 2700);
WIRE 16 -1 (-1000 2700)(-800 2700);
WIRE 16 -1 (-1000 2650)(-800 2650);
WIRE 16 -1 (400 2850)(400 2950);
WIRE 16 -1 (400 2800)(400 2850);
WIRE 16 -1 (200 2850)(400 2850);
WIRE 16 -1 (200 2800)(400 2800);
WIRE 16 -1 (1100 1150)(1100 1250);
WIRE 16 -1 (1100 1250)(1100 1300);
WIRE 16 -1 (1100 1250)(1300 1250);
WIRE 16 -1 (1100 1300)(1100 1350);
WIRE 16 -1 (1100 1300)(1300 1300);
WIRE 16 -1 (1100 1350)(1100 1400);
WIRE 16 -1 (1100 1350)(1300 1350);
WIRE 16 -1 (1100 1400)(1100 1450);
WIRE 16 -1 (1100 1400)(1300 1400);
WIRE 16 -1 (1100 1450)(1100 1500);
WIRE 16 -1 (1100 1450)(1300 1450);
WIRE 16 -1 (1100 1500)(1100 1550);
WIRE 16 -1 (1100 1500)(1300 1500);
WIRE 16 -1 (1100 1550)(1100 1600);
WIRE 16 -1 (1100 1550)(1300 1550);
WIRE 16 -1 (1100 1600)(1100 1650);
WIRE 16 -1 (1100 1600)(1300 1600);
WIRE 16 -1 (1100 1650)(1100 1700);
WIRE 16 -1 (1100 1650)(1300 1650);
WIRE 16 -1 (1100 1700)(1100 1750);
WIRE 16 -1 (1100 1700)(1300 1700);
WIRE 16 -1 (1100 1750)(1100 1800);
WIRE 16 -1 (1100 1750)(1300 1750);
WIRE 16 -1 (1100 1800)(1100 1850);
WIRE 16 -1 (1100 1800)(1300 1800);
WIRE 16 -1 (1100 1850)(1100 1900);
WIRE 16 -1 (1100 1850)(1300 1850);
WIRE 16 -1 (1100 1900)(1100 1950);
WIRE 16 -1 (1100 1900)(1300 1900);
WIRE 16 -1 (1100 1950)(1100 2000);
WIRE 16 -1 (1100 1950)(1300 1950);
WIRE 16 -1 (1100 2000)(1100 2050);
WIRE 16 -1 (1100 2000)(1300 2000);
WIRE 16 -1 (1100 2050)(1100 2100);
WIRE 16 -1 (1100 2050)(1300 2050);
WIRE 16 -1 (1100 2100)(1100 2150);
WIRE 16 -1 (1100 2100)(1300 2100);
WIRE 16 -1 (1100 2150)(1100 2200);
WIRE 16 -1 (1100 2150)(1300 2150);
WIRE 16 -1 (1100 2200)(1100 2250);
WIRE 16 -1 (1100 2200)(1300 2200);
WIRE 16 -1 (1100 2250)(1100 2300);
WIRE 16 -1 (1100 2250)(1300 2250);
WIRE 16 -1 (1100 2300)(1100 2350);
WIRE 16 -1 (1100 2300)(1300 2300);
WIRE 16 -1 (1100 2350)(1100 2400);
WIRE 16 -1 (1100 2350)(1300 2350);
WIRE 16 -1 (1100 2400)(1100 2450);
WIRE 16 -1 (1100 2400)(1300 2400);
WIRE 16 -1 (1100 2450)(1100 2500);
WIRE 16 -1 (1100 2450)(1300 2450);
WIRE 16 -1 (1100 2500)(1100 2550);
WIRE 16 -1 (1100 2500)(1300 2500);
WIRE 16 -1 (1100 2550)(1100 2600);
WIRE 16 -1 (1100 2550)(1300 2550);
WIRE 16 -1 (1100 2600)(1100 2650);
WIRE 16 -1 (1100 2600)(1300 2600);
WIRE 16 -1 (1100 2650)(1100 2700);
WIRE 16 -1 (1100 2650)(1300 2650);
WIRE 16 -1 (1100 2700)(1100 2750);
WIRE 16 -1 (1100 2700)(1300 2700);
WIRE 16 -1 (1100 2750)(1100 2800);
WIRE 16 -1 (1100 2750)(1300 2750);
WIRE 16 -1 (1100 2800)(1100 2850);
WIRE 16 -1 (1100 2800)(1300 2800);
WIRE 16 -1 (1100 2850)(1100 2900);
WIRE 16 -1 (1100 2850)(1300 2850);
WIRE 16 -1 (1100 2900)(1100 2950);
WIRE 16 -1 (1100 2900)(1300 2900);
WIRE 16 -1 (1100 2950)(1100 3000);
WIRE 16 -1 (1100 2950)(1300 2950);
WIRE 16 -1 (1100 3000)(1100 3050);
WIRE 16 -1 (1100 3000)(1300 3000);
WIRE 16 -1 (1100 3050)(1100 3100);
WIRE 16 -1 (1100 3050)(1300 3050);
WIRE 16 -1 (1100 3100)(1100 3150);
WIRE 16 -1 (1100 3100)(1300 3100);
WIRE 16 -1 (1100 3150)(1100 3200);
WIRE 16 -1 (1100 3150)(1300 3150);
WIRE 16 -1 (1100 3200)(1100 3250);
WIRE 16 -1 (1100 3200)(1300 3200);
WIRE 16 -1 (1100 3250)(1100 3300);
WIRE 16 -1 (1100 3250)(1300 3250);
WIRE 16 -1 (1100 3300)(1100 3350);
WIRE 16 -1 (1100 3300)(1300 3300);
WIRE 16 -1 (1100 3350)(1100 3400);
WIRE 16 -1 (1100 3350)(1300 3350);
WIRE 16 -1 (1100 3400)(1100 3450);
WIRE 16 -1 (1100 3400)(1300 3400);
WIRE 16 -1 (1100 3450)(1100 3500);
WIRE 16 -1 (1100 3450)(1300 3450);
WIRE 16 -1 (1100 3500)(1100 3550);
WIRE 16 -1 (1100 3500)(1300 3500);
WIRE 16 -1 (1100 3550)(1300 3550);
WIRE 16 -1 (-1150 2650)(-1150 2550);
WIRE 16 -1 (-1150 2550)(-1000 2550);
WIRE 16 -1 (-1000 2500)(-1000 2550);
WIRE 16 -1 (-1000 2550)(-800 2550);
WIRE 16 -1 (-1000 2500)(-800 2500);
WIRE 17 -1 (-3250 3850)(-3750 3850);
FORCEPROP 2 LAST SIG_NAME M_M_BA<1:0>
J 0
(-3725 3860);
DISPLAY 0.617021 (-3725 3860);
PAINT ORANGE (-3725 3860);
WIRE 17 -1 (-3250 3850)(-3250 3825);
WIRE 17 -1 (-3250 3775)(-3250 3825);
WIRE 17 -1 (-3250 3125)(-3250 3175);
WIRE 17 -1 (-3250 3275)(-3750 3275);
FORCEPROP 2 LAST SIG_NAME M_M_CS_N<7:0>
J 0
(-3725 3285);
DISPLAY 0.617021 (-3725 3285);
PAINT ORANGE (-3725 3285);
WIRE 17 -1 (-3250 3175)(-3250 3225);
WIRE 17 -1 (-3250 3225)(-3250 3275);
WIRE 17 -1 (-3750 4800)(-3250 4800);
FORCEPROP 2 LAST SIG_NAME M_M_MA<17:0>
J 0
(-3725 4810);
DISPLAY 0.617021 (-3725 4810);
PAINT ORANGE (-3725 4810);
WIRE 17 -1 (-3250 4775)(-3250 4800);
WIRE 17 -1 (-3250 4725)(-3250 4775);
WIRE 17 -1 (-3250 4675)(-3250 4725);
WIRE 17 -1 (-3250 4625)(-3250 4675);
WIRE 17 -1 (-3250 4575)(-3250 4625);
WIRE 17 -1 (-3250 4525)(-3250 4575);
WIRE 17 -1 (-3250 4475)(-3250 4525);
WIRE 17 -1 (-3250 4425)(-3250 4475);
WIRE 17 -1 (-3250 4375)(-3250 4425);
WIRE 17 -1 (-3250 4325)(-3250 4375);
WIRE 17 -1 (-3250 4275)(-3250 4325);
WIRE 17 -1 (-3250 4225)(-3250 4275);
WIRE 17 -1 (-3250 4175)(-3250 4225);
WIRE 17 -1 (-3250 4125)(-3250 4175);
WIRE 17 -1 (-3250 4075)(-3250 4125);
WIRE 17 -1 (-3250 4025)(-3250 4075);
WIRE 17 -1 (-3250 3975)(-3250 4025);
WIRE 17 -1 (-3250 3925)(-3250 3975);
WIRE 17 -1 (-3250 2375)(-3250 2425);
WIRE 17 -1 (-3250 2425)(-3250 2475);
WIRE 17 -1 (-3250 2475)(-3250 2525);
WIRE 17 -1 (-3250 2525)(-3250 2575);
WIRE 17 -1 (-3250 2575)(-3250 2625);
WIRE 17 -1 (-3250 2750)(-3750 2750);
FORCEPROP 2 LAST SIG_NAME M_M_ECC<7:0>
J 0
(-3725 2760);
DISPLAY 0.617021 (-3725 2760);
PAINT ORANGE (-3725 2760);
WIRE 17 -1 (-3250 2750)(-3250 2725);
WIRE 17 -1 (-3250 2625)(-3250 2675);
WIRE 17 -1 (-3250 2675)(-3250 2725);
WIRE 17 -1 (-3250 3050)(-3750 3050);
FORCEPROP 2 LAST SIG_NAME M_M_CKE<3:0>
J 0
(-3725 3060);
DISPLAY 0.617021 (-3725 3060);
PAINT ORANGE (-3725 3060);
WIRE 17 -1 (-3250 3050)(-3250 3025);
WIRE 17 -1 (-3250 2975)(-3250 3025);
WIRE 17 -1 (-3250 3750)(-3750 3750);
FORCEPROP 2 LAST SIG_NAME M_M_BG<1:0>
J 0
(-3725 3760);
DISPLAY 0.617021 (-3725 3760);
PAINT ORANGE (-3725 3760);
WIRE 17 -1 (-3250 3750)(-3250 3725);
WIRE 17 -1 (-3250 3675)(-3250 3725);
WIRE 17 -1 (-3250 2900)(-3750 2900);
FORCEPROP 2 LAST SIG_NAME M_M_ODT<3:0>
J 0
(-3725 2910);
DISPLAY 0.617021 (-3725 2910);
PAINT ORANGE (-3725 2910);
WIRE 17 -1 (-3250 2900)(-3250 2875);
WIRE 17 -1 (-3250 2825)(-3250 2875);
WIRE 17 -1 (-3700 3650)(-4350 3650);
FORCEPROP 2 LAST SIG_NAME M_M_CLK_DP<3:0>
J 0
(-4325 3660);
DISPLAY 0.617021 (-4325 3660);
PAINT ORANGE (-4325 3660);
WIRE 17 -1 (-3700 3650)(-3700 3575);
WIRE 17 -1 (-3700 3575)(-3700 3475);
WIRE 17 -1 (-3850 3600)(-4350 3600);
FORCEPROP 2 LAST SIG_NAME M_M_CLK_DN<3:0>
J 0
(-4325 3610);
DISPLAY 0.617021 (-4325 3610);
PAINT ORANGE (-4325 3610);
WIRE 17 -1 (-3850 3425)(-3850 3525);
WIRE 17 -1 (-3850 3525)(-3850 3600);
WIRE 17 -1 (-1200 4800)(-1650 4800);
FORCEPROP 2 LAST SIG_NAME M_M_DQ<63:0>
J 0
(-1610 4810);
DISPLAY 0.617021 (-1610 4810);
PAINT ORANGE (-1610 4810);
WIRE 17 -1 (-1650 4800)(-1650 4775);
WIRE 17 -1 (-1650 4725)(-1650 4775);
WIRE 17 -1 (-1650 4675)(-1650 4725);
WIRE 17 -1 (-1650 4625)(-1650 4675);
WIRE 17 -1 (-1650 4575)(-1650 4625);
WIRE 17 -1 (-1650 4525)(-1650 4575);
WIRE 17 -1 (-1650 4475)(-1650 4525);
WIRE 17 -1 (-1650 4425)(-1650 4475);
WIRE 17 -1 (-1650 4375)(-1650 4425);
WIRE 17 -1 (-1650 4325)(-1650 4375);
WIRE 17 -1 (-1650 4275)(-1650 4325);
WIRE 17 -1 (-1650 4225)(-1650 4275);
WIRE 17 -1 (-1650 4175)(-1650 4225);
WIRE 17 -1 (-1650 4125)(-1650 4175);
WIRE 17 -1 (-1650 4075)(-1650 4125);
WIRE 17 -1 (-1650 4025)(-1650 4075);
WIRE 17 -1 (-1650 3975)(-1650 4025);
WIRE 17 -1 (-1650 3925)(-1650 3975);
WIRE 17 -1 (-1650 3875)(-1650 3925);
WIRE 17 -1 (-1650 3825)(-1650 3875);
WIRE 17 -1 (-1650 3775)(-1650 3825);
WIRE 17 -1 (-1650 3725)(-1650 3775);
WIRE 17 -1 (-1650 3675)(-1650 3725);
WIRE 17 -1 (-1650 3625)(-1650 3675);
WIRE 17 -1 (-1650 3575)(-1650 3625);
WIRE 17 -1 (-1650 3525)(-1650 3575);
WIRE 17 -1 (-1650 3475)(-1650 3525);
WIRE 17 -1 (-1650 3425)(-1650 3475);
WIRE 17 -1 (-1650 3375)(-1650 3425);
WIRE 17 -1 (-1650 3325)(-1650 3375);
WIRE 17 -1 (-1650 3275)(-1650 3325);
WIRE 17 -1 (-1650 3225)(-1650 3275);
WIRE 17 -1 (-1650 3175)(-1650 3225);
WIRE 17 -1 (-1650 3125)(-1650 3175);
WIRE 17 -1 (-1650 3075)(-1650 3125);
WIRE 17 -1 (-1650 3025)(-1650 3075);
WIRE 17 -1 (-1650 2975)(-1650 3025);
WIRE 17 -1 (-1650 2925)(-1650 2975);
WIRE 17 -1 (-1650 2875)(-1650 2925);
WIRE 17 -1 (-1650 2825)(-1650 2875);
WIRE 17 -1 (-1650 2775)(-1650 2825);
WIRE 17 -1 (-1650 2725)(-1650 2775);
WIRE 17 -1 (-1650 2675)(-1650 2725);
WIRE 17 -1 (-1650 2625)(-1650 2675);
WIRE 17 -1 (-1650 2575)(-1650 2625);
WIRE 17 -1 (-1650 2525)(-1650 2575);
WIRE 17 -1 (-1650 2475)(-1650 2525);
WIRE 17 -1 (-1650 2425)(-1650 2475);
WIRE 17 -1 (-1650 2375)(-1650 2425);
WIRE 17 -1 (-1650 2325)(-1650 2375);
WIRE 17 -1 (-1650 2275)(-1650 2325);
WIRE 17 -1 (-1650 1625)(-1650 1675);
WIRE 17 -1 (-1650 2225)(-1650 2275);
WIRE 17 -1 (-1650 2175)(-1650 2225);
WIRE 17 -1 (-1650 1675)(-1650 1725);
WIRE 17 -1 (-1650 1725)(-1650 1775);
WIRE 17 -1 (-1650 2125)(-1650 2175);
WIRE 17 -1 (-1650 2075)(-1650 2125);
WIRE 17 -1 (-1650 1775)(-1650 1825);
WIRE 17 -1 (-1650 1825)(-1650 1875);
WIRE 17 -1 (-1650 2025)(-1650 2075);
WIRE 17 -1 (-1650 1975)(-1650 2025);
WIRE 17 -1 (-1650 1875)(-1650 1925);
WIRE 17 -1 (-1650 1925)(-1650 1975);
WIRE 17 -1 (1550 5200)(750 5200);
FORCEPROP 2 LAST SIG_NAME M_M_DQS_DP<17:0>
J 0
(1000 5210);
DISPLAY 0.617021 (1000 5210);
PAINT ORANGE (1000 5210);
WIRE 17 -1 (750 5175)(750 5200);
WIRE 17 -1 (750 5075)(750 5175);
WIRE 17 -1 (750 4975)(750 5075);
WIRE 17 -1 (750 4875)(750 4975);
WIRE 17 -1 (750 4775)(750 4875);
WIRE 17 -1 (750 4675)(750 4775);
WIRE 17 -1 (750 4575)(750 4675);
WIRE 17 -1 (750 4475)(750 4575);
WIRE 17 -1 (750 4375)(750 4475);
WIRE 17 -1 (750 4275)(750 4375);
WIRE 17 -1 (750 4175)(750 4275);
WIRE 17 -1 (750 4075)(750 4175);
WIRE 17 -1 (750 3975)(750 4075);
WIRE 17 -1 (750 3875)(750 3975);
WIRE 17 -1 (750 3775)(750 3875);
WIRE 17 -1 (750 3675)(750 3775);
WIRE 17 -1 (750 3575)(750 3675);
WIRE 17 -1 (750 3475)(750 3575);
WIRE 17 -1 (1550 5150)(950 5150);
FORCEPROP 2 LAST SIG_NAME M_M_DQS_DN<17:0>
J 0
(1000 5160);
DISPLAY 0.617021 (1000 5160);
PAINT ORANGE (1000 5160);
WIRE 17 -1 (950 5125)(950 5150);
WIRE 17 -1 (950 5025)(950 5125);
WIRE 17 -1 (950 4925)(950 5025);
WIRE 17 -1 (950 4825)(950 4925);
WIRE 17 -1 (950 4725)(950 4825);
WIRE 17 -1 (950 4625)(950 4725);
WIRE 17 -1 (950 4525)(950 4625);
WIRE 17 -1 (950 4425)(950 4525);
WIRE 17 -1 (950 4325)(950 4425);
WIRE 17 -1 (950 4225)(950 4325);
WIRE 17 -1 (950 4125)(950 4225);
WIRE 17 -1 (950 4025)(950 4125);
WIRE 17 -1 (950 3925)(950 4025);
WIRE 17 -1 (950 3825)(950 3925);
WIRE 17 -1 (950 3725)(950 3825);
WIRE 17 -1 (950 3625)(950 3725);
WIRE 17 -1 (950 3425)(950 3525);
WIRE 17 -1 (950 3525)(950 3625);
WIRE 16 -1 (850 3500)(450 3500);
WIRE 16 -1 (650 3450)(450 3450);
WIRE 16 -1 (850 3400)(450 3400);
WIRE 16 -1 (-1750 4350)(-1950 4350);
WIRE 16 -1 (-1750 4400)(-1950 4400);
WIRE 16 -1 (-2950 2100)(-3975 2100);
FORCEPROP 2 LAST SIG_NAME M_M_ALERT_N
J 0
(-3925 2110);
DISPLAY 0.617021 (-3925 2110);
PAINT ORANGE (-3925 2110);
WIRE 16 -1 (-1750 3850)(-1950 3850);
WIRE 16 -1 (-2950 4600)(-3150 4600);
WIRE 16 -1 (-1750 4300)(-1950 4300);
WIRE 16 -1 (-1750 4250)(-1950 4250);
WIRE 16 -1 (650 5150)(450 5150);
WIRE 16 -1 (650 4350)(450 4350);
WIRE 16 -1 (850 4300)(450 4300);
WIRE 16 -1 (650 4250)(450 4250);
WIRE 16 -1 (850 4200)(450 4200);
WIRE 16 -1 (650 4150)(450 4150);
WIRE 16 -1 (850 4100)(450 4100);
WIRE 16 -1 (850 5100)(450 5100);
WIRE 16 -1 (650 5050)(450 5050);
WIRE 16 -1 (850 5000)(450 5000);
WIRE 16 -1 (650 4950)(450 4950);
WIRE 16 -1 (850 4900)(450 4900);
WIRE 16 -1 (650 4850)(450 4850);
WIRE 16 -1 (850 4800)(450 4800);
WIRE 16 -1 (650 4750)(450 4750);
WIRE 16 -1 (850 4700)(450 4700);
WIRE 16 -1 (650 4650)(450 4650);
WIRE 16 -1 (850 4600)(450 4600);
WIRE 16 -1 (650 4550)(450 4550);
WIRE 16 -1 (850 4500)(450 4500);
WIRE 16 -1 (650 4450)(450 4450);
WIRE 16 -1 (850 4400)(450 4400);
WIRE 16 -1 (650 4050)(450 4050);
WIRE 16 -1 (850 4000)(450 4000);
WIRE 16 -1 (650 3950)(450 3950);
WIRE 16 -1 (850 3900)(450 3900);
WIRE 16 -1 (650 3850)(450 3850);
WIRE 16 -1 (850 3800)(450 3800);
WIRE 16 -1 (650 3750)(450 3750);
WIRE 16 -1 (850 3700)(450 3700);
WIRE 16 -1 (650 3650)(450 3650);
WIRE 16 -1 (850 3600)(450 3600);
WIRE 16 -1 (650 3550)(450 3550);
WIRE 16 -1 (-1750 4750)(-1950 4750);
WIRE 16 -1 (-1750 4650)(-1950 4650);
WIRE 16 -1 (-1750 4700)(-1950 4700);
WIRE 16 -1 (-1750 4600)(-1950 4600);
WIRE 16 -1 (-1750 4500)(-1950 4500);
WIRE 16 -1 (-1750 4450)(-1950 4450);
WIRE 16 -1 (-1750 4100)(-1950 4100);
WIRE 16 -1 (-1750 4150)(-1950 4150);
WIRE 16 -1 (-1750 4200)(-1950 4200);
WIRE 16 -1 (-1750 4550)(-1950 4550);
WIRE 16 -1 (-2950 4100)(-3150 4100);
WIRE 16 -1 (-2950 4700)(-3150 4700);
WIRE 16 -1 (-2950 4650)(-3150 4650);
WIRE 16 -1 (-2950 4450)(-3150 4450);
WIRE 16 -1 (-2950 4400)(-3150 4400);
WIRE 16 -1 (-2950 4350)(-3150 4350);
WIRE 16 -1 (-2950 4300)(-3150 4300);
WIRE 16 -1 (-2950 4250)(-3150 4250);
WIRE 16 -1 (-2950 4200)(-3150 4200);
WIRE 16 -1 (-2950 4150)(-3150 4150);
WIRE 16 -1 (-2950 4750)(-3150 4750);
WIRE 16 -1 (-2950 4550)(-3150 4550);
WIRE 16 -1 (-2950 4500)(-3150 4500);
WIRE 16 -1 (-1750 3950)(-1950 3950);
WIRE 16 -1 (-1750 4000)(-1950 4000);
WIRE 16 -1 (-1750 4050)(-1950 4050);
WIRE 16 -1 (-1750 3600)(-1950 3600);
WIRE 16 -1 (-1750 3650)(-1950 3650);
WIRE 16 -1 (-1750 3700)(-1950 3700);
WIRE 16 -1 (-1750 3750)(-1950 3750);
WIRE 16 -1 (-1750 3800)(-1950 3800);
WIRE 16 -1 (-1750 3900)(-1950 3900);
WIRE 16 -1 (-1750 3100)(-1950 3100);
WIRE 16 -1 (-1750 3500)(-1950 3500);
WIRE 16 -1 (-1750 3400)(-1950 3400);
WIRE 16 -1 (-1750 3350)(-1950 3350);
WIRE 16 -1 (-1750 3150)(-1950 3150);
WIRE 16 -1 (-1750 3200)(-1950 3200);
WIRE 16 -1 (-1750 3250)(-1950 3250);
WIRE 16 -1 (-1750 3300)(-1950 3300);
WIRE 16 -1 (-1750 3450)(-1950 3450);
WIRE 16 -1 (-1750 3550)(-1950 3550);
WIRE 16 -1 (-1750 2700)(-1950 2700);
WIRE 16 -1 (-1750 2900)(-1950 2900);
WIRE 16 -1 (-1750 2950)(-1950 2950);
WIRE 16 -1 (-1750 2600)(-1950 2600);
WIRE 16 -1 (-1750 2650)(-1950 2650);
WIRE 16 -1 (-1750 2750)(-1950 2750);
WIRE 16 -1 (-1750 2800)(-1950 2800);
WIRE 16 -1 (-1750 2850)(-1950 2850);
WIRE 16 -1 (-1750 3000)(-1950 3000);
WIRE 16 -1 (-1750 3050)(-1950 3050);
WIRE 16 -1 (-1750 2400)(-1950 2400);
WIRE 16 -1 (-1750 2350)(-1950 2350);
WIRE 16 -1 (-1750 2300)(-1950 2300);
WIRE 16 -1 (-1750 2200)(-1950 2200);
WIRE 16 -1 (-1750 2150)(-1950 2150);
WIRE 16 -1 (-1750 2100)(-1950 2100);
WIRE 16 -1 (-1750 2450)(-1950 2450);
WIRE 16 -1 (-1750 2050)(-1950 2050);
WIRE 16 -1 (-1750 2250)(-1950 2250);
WIRE 16 -1 (-1750 2500)(-1950 2500);
WIRE 16 -1 (-1750 2550)(-1950 2550);
WIRE 16 -1 (-1750 2000)(-1950 2000);
WIRE 16 -1 (-1750 1850)(-1950 1850);
WIRE 16 -1 (-1750 1800)(-1950 1800);
WIRE 16 -1 (-1750 1750)(-1950 1750);
WIRE 16 -1 (-1750 1700)(-1950 1700);
WIRE 16 -1 (-1750 1600)(-1950 1600);
WIRE 16 -1 (-1750 1650)(-1950 1650);
WIRE 16 -1 (-1750 1900)(-1950 1900);
WIRE 16 -1 (-1750 1950)(-1950 1950);
WIRE 16 -1 (-2950 2050)(-3950 2050);
FORCEPROP 2 LAST SIG_NAME M_M_ACT_N
J 0
(-3925 2060);
DISPLAY 0.617021 (-3925 2060);
PAINT ORANGE (-3925 2060);
WIRE 16 -1 (-2950 3400)(-3750 3400);
WIRE 16 -1 (-3750 3500)(-2950 3500);
WIRE 16 -1 (-2950 3550)(-3600 3550);
WIRE 16 -1 (-2950 3450)(-3600 3450);
WIRE 16 -1 (-2950 3950)(-3150 3950);
WIRE 16 -1 (-2950 3100)(-3150 3100);
WIRE 16 -1 (-2950 2950)(-3150 2950);
WIRE 16 -1 (-2950 2850)(-3150 2850);
WIRE 16 -1 (-2950 2800)(-3150 2800);
WIRE 16 -1 (-2950 2700)(-3150 2700);
WIRE 16 -1 (-2950 4000)(-3150 4000);
WIRE 16 -1 (-2950 3750)(-3150 3750);
WIRE 16 -1 (-2950 3700)(-3150 3700);
WIRE 16 -1 (-2950 3650)(-3150 3650);
WIRE 16 -1 (-2950 3000)(-3150 3000);
WIRE 16 -1 (-2950 2350)(-3150 2350);
WIRE 16 -1 (-2950 2400)(-3150 2400);
WIRE 16 -1 (-2950 2450)(-3150 2450);
WIRE 16 -1 (-2950 2500)(-3150 2500);
WIRE 16 -1 (-2950 2550)(-3150 2550);
WIRE 16 -1 (-2950 2600)(-3150 2600);
WIRE 16 -1 (-2950 2650)(-3150 2650);
WIRE 16 -1 (-2950 4050)(-3150 4050);
WIRE 16 -1 (-2950 3900)(-3150 3900);
WIRE 16 -1 (-2950 3150)(-3150 3150);
WIRE 16 -1 (-2950 3200)(-3150 3200);
WIRE 16 -1 (-2950 3250)(-3150 3250);
WIRE 16 -1 (-2950 3800)(-3150 3800);
WIRE 16 -1 (-3100 3325)(-3750 3325);
FORCEPROP 2 LAST SIG_NAME M_M_C<2>
J 0
(-3725 3335);
DISPLAY 0.617021 (-3725 3335);
PAINT ORANGE (-3725 3335);
WIRE 16 -1 (-3100 3325)(-3100 3300);
WIRE 16 -1 (-3100 3300)(-2950 3300);
WIRE 16 -1 (-3350 2650)(-3750 2650);
FORCEPROP 2 LAST SIG_NAME M_KLM_RST_N
J 0
(-3725 2660);
DISPLAY 0.617021 (-3725 2660);
PAINT ORANGE (-3725 2660);
WIRE 16 -1 (-3350 2200)(-3350 2650);
WIRE 16 -1 (-2950 2200)(-3350 2200);
WIRE 16 -1 (-3300 2700)(-3750 2700);
FORCEPROP 2 LAST SIG_NAME M_M_PAR
J 0
(-3725 2710);
DISPLAY 0.617021 (-3725 2710);
PAINT ORANGE (-3725 2710);
WIRE 16 -1 (-3300 2250)(-3300 2700);
WIRE 16 -1 (-2950 2250)(-3300 2250);
WIRE 16 -1 (-3400 2450)(-4125 2450);
FORCEPROP 2 LAST SIG_NAME FM_DIMM_EVENT_COD_N
J 0
(-4121 2452);
DISPLAY 0.617021 (-4121 2452);
PAINT ORANGE (-4121 2452);
WIRE 16 -1 (-3400 2150)(-3400 2450);
WIRE 16 -1 (-3400 2150)(-2950 2150);
WIRE 16 -1 (-3800 1300)(-2950 1300);
FORCEPROP 2 LAST SIG_NAME FM_ADR_COMPLETE_KLM_N
J 0
(-3750 1310);
DISPLAY 0.617021 (-3750 1310);
PAINT ORANGE (-3750 1310);
WIRE 16 -1 (-2950 1750)(-3750 1750);
WIRE 16 -1 (-3750 1700)(-2950 1700);
FORCEPROP 2 LAST SIG_NAME SMB_DDR_KLM_VPP_SCL
J 0
(-3710 1710);
DISPLAY 0.617021 (-3710 1710);
PAINT ORANGE (-3710 1710);
WIRE 16 -1 (-3800 1450)(-2950 1450);
FORCEPROP 2 LAST SIG_NAME TP_CH_M_DIMM_M1_RFU_1
J 0
(-3750 1460);
DISPLAY 0.617021 (-3750 1460);
PAINT ORANGE (-3750 1460);
FORCEPROP 2 LASTPROP $XRERR UNIQUE?
J 0
(-4040 1450);
DISPLAY 0.638298 (-4040 1450);
PAINT MONO (-4040 1450);
DISPLAY INVISIBLE (-4040 1450);
WIRE 16 -1 (-3800 1400)(-2950 1400);
FORCEPROP 2 LAST SIG_NAME TP_CH_M_DIMM_M1_RFU_0
J 0
(-3750 1410);
DISPLAY 0.617021 (-3750 1410);
PAINT ORANGE (-3750 1410);
FORCEPROP 2 LASTPROP $XRERR UNIQUE?
J 0
(-4040 1400);
DISPLAY 0.638298 (-4040 1400);
PAINT MONO (-4040 1400);
DISPLAY INVISIBLE (-4040 1400);
WIRE 16 -1 (-3800 1500)(-2950 1500);
FORCEPROP 2 LAST SIG_NAME TP_CH_M_DIMM_M1_RFU_2
J 0
(-3750 1510);
DISPLAY 0.617021 (-3750 1510);
PAINT ORANGE (-3750 1510);
FORCEPROP 2 LASTPROP $XRERR UNIQUE?
J 0
(-4040 1500);
DISPLAY 0.638298 (-4040 1500);
PAINT MONO (-4040 1500);
DISPLAY INVISIBLE (-4040 1500);
WIRE 16 -1 (-4650 1600)(-4650 1500);
WIRE 16 -1 (-4650 1600)(-4750 1600);
WIRE 16 -1 (-2950 1600)(-4650 1600);
FORCEPROP 2 LAST SIG_NAME M_M_VREF
J 0
(-3725 1610);
DISPLAY 0.617021 (-3725 1610);
PAINT ORANGE (-3725 1610);
DOT 1 (-1000 2350);
DOT 1 (1100 3500);
DOT 1 (1100 3450);
DOT 1 (1100 3400);
DOT 1 (2500 1950);
DOT 1 (1100 2650);
DOT 1 (1100 2600);
DOT 1 (2500 2950);
DOT 1 (-4650 1600);
DOT 1 (-3100 1900);
DOT 1 (1100 3350);
DOT 1 (2500 2350);
DOT 1 (2500 2150);
DOT 1 (2500 1350);
DOT 1 (2500 3500);
DOT 1 (2500 3450);
DOT 1 (2500 3400);
DOT 1 (2500 3350);
DOT 1 (2500 3300);
DOT 1 (2500 3250);
DOT 1 (2500 3200);
DOT 1 (2500 3150);
DOT 1 (2500 3100);
DOT 1 (2500 3050);
DOT 1 (2500 3000);
DOT 1 (2500 2900);
DOT 1 (2500 2850);
DOT 1 (2500 2800);
DOT 1 (2500 2650);
DOT 1 (2500 2700);
DOT 1 (2500 2600);
DOT 1 (2500 2550);
DOT 1 (2500 2500);
DOT 1 (2500 2450);
DOT 1 (2500 2400);
DOT 1 (2500 2300);
DOT 1 (2500 2250);
DOT 1 (2500 2200);
DOT 1 (2500 2100);
DOT 1 (2500 2050);
DOT 1 (2500 2000);
DOT 1 (2500 1900);
DOT 1 (2500 1850);
DOT 1 (2500 1800);
DOT 1 (2500 1750);
DOT 1 (2500 1700);
DOT 1 (2500 1650);
DOT 1 (2500 1600);
DOT 1 (2500 1550);
DOT 1 (2500 1500);
DOT 1 (2500 1450);
DOT 1 (2500 1400);
DOT 1 (2500 1300);
DOT 1 (2500 1250);
DOT 1 (1100 3300);
DOT 1 (1100 3200);
DOT 1 (1100 3250);
DOT 1 (1100 3100);
DOT 1 (1100 3050);
DOT 1 (1100 3000);
DOT 1 (1100 2950);
DOT 1 (1100 2900);
DOT 1 (1100 2850);
DOT 1 (1100 2800);
DOT 1 (1100 2750);
DOT 1 (1100 2700);
DOT 1 (1100 2550);
DOT 1 (1100 2500);
DOT 1 (1100 2450);
DOT 1 (1100 2400);
DOT 1 (1100 2350);
DOT 1 (1100 2300);
DOT 1 (1100 2250);
DOT 1 (1100 2200);
DOT 1 (1100 2150);
DOT 1 (1100 2100);
DOT 1 (1100 2050);
DOT 1 (1100 2000);
DOT 1 (1100 1950);
DOT 1 (1100 1900);
DOT 1 (1100 1850);
DOT 1 (1100 1800);
DOT 1 (1100 1750);
DOT 1 (1100 1700);
DOT 1 (1100 1650);
DOT 1 (1100 1600);
DOT 1 (1100 1550);
DOT 1 (1100 1500);
DOT 1 (1100 1450);
DOT 1 (1100 1400);
DOT 1 (1100 1350);
DOT 1 (1100 1300);
DOT 1 (1100 1250);
DOT 1 (-3100 1950);
DOT 1 (-1000 2850);
DOT 1 (-1000 2800);
DOT 1 (-1000 2750);
DOT 1 (-1000 2200);
DOT 1 (-1000 2150);
DOT 1 (-1000 2100);
DOT 1 (-1000 2050);
DOT 1 (-1000 2000);
DOT 1 (-1000 1950);
DOT 1 (-1000 1900);
DOT 1 (-1000 1850);
DOT 1 (-1000 1800);
DOT 1 (-1000 1750);
DOT 1 (-1000 1650);
DOT 1 (-1000 1600);
DOT 1 (-1000 1550);
DOT 1 (-1000 1500);
DOT 1 (-1000 1450);
DOT 1 (-1000 1400);
DOT 1 (-1000 1350);
DOT 1 (-1000 1250);
DOT 1 (-1000 1300);
DOT 1 (-1000 2550);
DOT 1 (-1000 1200);
DOT 1 (-1000 2700);
DOT 1 (-1000 1700);
DOT 1 (-1000 2300);
DOT 1 (-1000 2400);
DOT 1 (400 2850);
DOT 1 (-1000 2250);
DOT 1 (1100 3150);
DOT 1 (2500 2750);
FORCENOTE
PVDDQ (SINGLE SIDE) CAP: 10UF X1, 22UF X50
(-2750 5250) 0;
DISPLAY LEFT (-2750 5250);
DISPLAY 1.021277 (-2750 5250);
PAINT PURPLE (-2750 5250);
FORCENOTE
PVDDQ (DOUBLE SIDE) CAP: 100UF X8, 47UF X41
(-2750 5200) 0;
DISPLAY LEFT (-2750 5200);
DISPLAY 1.021277 (-2750 5200);
PAINT PURPLE (-2750 5200);
FORCENOTE
PVTT CAP: 100UF X2, 47UF X1
(-2750 5300) 0;
DISPLAY LEFT (-2750 5300);
DISPLAY 1.021277 (-2750 5300);
PAINT PURPLE (-2750 5300);
FORCENOTE
CAP BETWEEN DIMM
(-2750 5425) 0;
DISPLAY LEFT (-2750 5425);
DISPLAY 1.276596 (-2750 5425);
PAINT PURPLE (-2750 5425);
FORCENOTE
PVPP CAP: 10UF X12
(-2750 5350) 0;
DISPLAY LEFT (-2750 5350);
DISPLAY 1.021277 (-2750 5350);
PAINT PURPLE (-2750 5350);
FORCENOTE
SMBUS ADDR: 0XAA
(-5225 909) 0;
DISPLAY LEFT (-5225 909);
DISPLAY 1.957447 (-5225 909);
PAINT PURPLE (-5225 909);
FORCENOTE
PLACE CAP NEAR DIMM CONNECTOR
(-5288 1052) 0;
DISPLAY LEFT (-5288 1052);
DISPLAY 1.595745 (-5288 1052);
PAINT PURPLE (-5288 1052);
QUIT
